FILE_TYPE = MACRO_DRAWING;
SET COLOR_WIRE YELLOW;
SET COLOR_PROP ORANGE;
SET COLOR_DOT WHITE;
SET COLOR_ARC YELLOW;
SET COLOR_BODY GREEN;
SET COLOR_NOTE PURPLE;
SET PROP_DISPLAY VALUE;
SET PAGE_NUMBER P439;
FORCEADD OFFPAGE..1
(-4275 2000);
FORCEPROP 2 LAST $XR0 320 
J 0
(-4527 2000);
DISPLAY 0.638298 (-4527 2000);
PAINT MONO (-4527 2000);
FORCEPROP 2 LAST CDS_LIB standard
J 0
(-4275 2000);
DISPLAY INVISIBLE (-4275 2000);
FORCEPROP 1 LAST OFFPAGE TRUE
J 0
(-3950 1875);
DISPLAY 0.872340 (-3950 1875);
DISPLAY INVISIBLE (-3950 1875);
FORCEPROP 1 LAST COMMENT_BODY TRUE
J 0
(-4150 1900);
DISPLAY 0.872340 (-4150 1900);
PAINT GREEN (-4150 1900);
DISPLAY INVISIBLE (-4150 1900);
FORCEPROP 2 LAST PATH I1
J 0
(-4525 2050);
DISPLAY 0.680851 (-4525 2050);
DISPLAY INVISIBLE (-4525 2050);
FORCEADD TAP..1
R 2
(-3075 825);
FORCEPROP 3 LASTPIN (-3025 825) SIG_NAME P5E_CPU1_P0_TX_BUF_DP<6>
J 0
(-3015 835);
DISPLAY 0.659574 (-3015 835);
PAINT MONO (-3015 835);
DISPLAY INVISIBLE (-3015 835);
FORCEPROP 1 LASTPIN (-3025 825) BN 6
J 2
(-3013 833);
DISPLAY 0.680851 (-3013 833);
PAINT GREEN (-3013 833);
FORCEPROP 2 LAST CDS_LIB standard
J 0
(-3075 825);
DISPLAY INVISIBLE (-3075 825);
FORCEPROP 1 LAST BODY_TYPE PLUMBING
J 2
(-3075 875);
DISPLAY 0.872340 (-3075 875);
PAINT GREEN (-3075 875);
DISPLAY INVISIBLE (-3075 875);
FORCEPROP 1 LAST HDL_TAP TRUE
J 2
(-3400 700);
DISPLAY 0.872340 (-3400 700);
DISPLAY INVISIBLE (-3400 700);
FORCEPROP 1 LAST PATH I10
J 2
(-3073 825);
DISPLAY 0.872340 (-3073 825);
PAINT GREEN (-3073 825);
DISPLAY INVISIBLE (-3073 825);
FORCEADD TAP..1
R 2
(-7675 1850);
FORCEPROP 3 LASTPIN (-7625 1850) SIG_NAME P5E_CPU1_P0_TX_BUF_DP<9>
J 0
(-7615 1860);
DISPLAY 0.659574 (-7615 1860);
PAINT MONO (-7615 1860);
DISPLAY INVISIBLE (-7615 1860);
FORCEPROP 1 LASTPIN (-7625 1850) BN 9
J 2
(-7613 1858);
DISPLAY 0.680851 (-7613 1858);
PAINT GREEN (-7613 1858);
FORCEPROP 2 LAST CDS_LIB standard
J 0
(-7675 1850);
DISPLAY INVISIBLE (-7675 1850);
FORCEPROP 1 LAST BODY_TYPE PLUMBING
J 2
(-7675 1900);
DISPLAY 0.872340 (-7675 1900);
PAINT GREEN (-7675 1900);
DISPLAY INVISIBLE (-7675 1900);
FORCEPROP 1 LAST HDL_TAP TRUE
J 2
(-8000 1725);
DISPLAY 0.872340 (-8000 1725);
DISPLAY INVISIBLE (-8000 1725);
FORCEPROP 1 LAST PATH I100
J 2
(-7673 1850);
DISPLAY 0.872340 (-7673 1850);
PAINT GREEN (-7673 1850);
DISPLAY INVISIBLE (-7673 1850);
FORCEADD TAP..1
R 2
(-7675 2050);
FORCEPROP 3 LASTPIN (-7625 2050) SIG_NAME P5E_CPU1_P0_TX_BUF_DP<8>
J 0
(-7615 2060);
DISPLAY 0.659574 (-7615 2060);
PAINT MONO (-7615 2060);
DISPLAY INVISIBLE (-7615 2060);
FORCEPROP 1 LASTPIN (-7625 2050) BN 8
J 2
(-7613 2058);
DISPLAY 0.680851 (-7613 2058);
PAINT GREEN (-7613 2058);
FORCEPROP 2 LAST CDS_LIB standard
J 0
(-7675 2050);
DISPLAY INVISIBLE (-7675 2050);
FORCEPROP 1 LAST BODY_TYPE PLUMBING
J 2
(-7675 2100);
DISPLAY 0.872340 (-7675 2100);
PAINT GREEN (-7675 2100);
DISPLAY INVISIBLE (-7675 2100);
FORCEPROP 1 LAST HDL_TAP TRUE
J 2
(-8000 1925);
DISPLAY 0.872340 (-8000 1925);
DISPLAY INVISIBLE (-8000 1925);
FORCEPROP 1 LAST PATH I101
J 2
(-7673 2050);
DISPLAY 0.872340 (-7673 2050);
PAINT GREEN (-7673 2050);
DISPLAY INVISIBLE (-7673 2050);
FORCEADD Q_CAP_DIFFBUS..2
R 2
(-6950 1850);
FORCEPROP 1 LAST LOCATION C6647
J 2
(-6675 1850);
DISPLAY 0.723404 (-6675 1850);
PAINT GREEN (-6675 1850);
FORCEPROP 2 LAST $SEC 1
J 2
(-6775 1925);
DISPLAY 0.680851 (-6775 1925);
PAINT MONO (-6775 1925);
DISPLAY INVISIBLE (-6775 1925);
FORCEPROP 2 LAST CDS_SEC 1
J 2
(-6775 1925);
DISPLAY 0.680851 (-6775 1925);
DISPLAY INVISIBLE (-6775 1925);
FORCEPROP 2 LASTPIN (-6875 1850) $PN 1
J 0
(-6865 1860);
DISPLAY 0.808511 (-6865 1860);
FORCEPROP 2 LASTPIN (-7025 1850) $PN 2
J 2
(-7035 1860);
DISPLAY 0.808511 (-7035 1860);
FORCEPROP 2 LAST VALUE DIFF BUS_0.22UF
J 2
(-7100 1850);
DISPLAY 0.553191 (-7100 1850);
FORCEPROP 1 LAST CDS_LMAN_SYM_OUTLINE -25,50,25,-50
J 2
(-6950 1850);
DISPLAY 0.468085 (-6950 1850);
PAINT GREEN (-6950 1850);
DISPLAY INVISIBLE (-6950 1850);
FORCEPROP 2 LAST CDS_LIB pure_quanta
J 2
(-6950 1850);
DISPLAY INVISIBLE (-6950 1850);
FORCEPROP 1 LAST PIN_NAMES_ROTATE TRUE
J 2
(-6950 1850);
DISPLAY 0.489362 (-6950 1850);
PAINT GREEN (-6950 1850);
DISPLAY INVISIBLE (-6950 1850);
FORCEPROP 2 LAST VOLTAGE 6.3V
J 2
(-7300 1900);
DISPLAY 0.553191 (-7300 1900);
DISPLAY INVISIBLE (-7300 1900);
FORCEPROP 1 LAST MATERIAL X6S
J 2
(-6941 1929);
DISPLAY 0.574468 (-6941 1929);
PAINT GREEN (-6941 1929);
DISPLAY INVISIBLE (-6941 1929);
FORCEPROP 2 LAST PACK_TYPE C0201
J 2
(-7125 1900);
DISPLAY 0.553191 (-7125 1900);
DISPLAY INVISIBLE (-7125 1900);
FORCEPROP 2 LAST TOLERANCE 20%
J 2
(-7025 1900);
DISPLAY 0.553191 (-7025 1900);
DISPLAY INVISIBLE (-7025 1900);
FORCEPROP 1 LAST PATH I102
J 2
(-6950 1850);
DISPLAY 0.723404 (-6950 1850);
DISPLAY INVISIBLE (-6950 1850);
FORCEPROP 1 LAST PART_NUMBER SP_CH4221MEE01
J 2
(-7066 1938);
DISPLAY 0.574468 (-7066 1938);
PAINT GREEN (-7066 1938);
DISPLAY INVISIBLE (-7066 1938);
FORCEPROP 1 LAST LOCATION C6647
J 0
(-6700 1925);
DISPLAY 1.021277 (-6700 1925);
DISPLAY INVISIBLE (-6700 1925);
FORCEADD Q_CAP_DIFFBUS..2
R 2
(-6950 1800);
FORCEPROP 1 LAST LOCATION C6648
J 2
(-6675 1800);
DISPLAY 0.723404 (-6675 1800);
PAINT GREEN (-6675 1800);
FORCEPROP 2 LAST $SEC 1
J 2
(-6775 1875);
DISPLAY 0.680851 (-6775 1875);
PAINT MONO (-6775 1875);
DISPLAY INVISIBLE (-6775 1875);
FORCEPROP 2 LAST CDS_SEC 1
J 2
(-6775 1875);
DISPLAY 0.680851 (-6775 1875);
DISPLAY INVISIBLE (-6775 1875);
FORCEPROP 2 LASTPIN (-6875 1800) $PN 1
J 0
(-6865 1810);
DISPLAY 0.808511 (-6865 1810);
FORCEPROP 2 LASTPIN (-7025 1800) $PN 2
J 2
(-7035 1810);
DISPLAY 0.808511 (-7035 1810);
FORCEPROP 2 LAST VALUE DIFF BUS_0.22UF
J 2
(-7100 1800);
DISPLAY 0.553191 (-7100 1800);
FORCEPROP 1 LAST CDS_LMAN_SYM_OUTLINE -25,50,25,-50
J 2
(-6950 1800);
DISPLAY 0.468085 (-6950 1800);
PAINT GREEN (-6950 1800);
DISPLAY INVISIBLE (-6950 1800);
FORCEPROP 2 LAST CDS_LIB pure_quanta
J 2
(-6950 1800);
DISPLAY INVISIBLE (-6950 1800);
FORCEPROP 1 LAST PIN_NAMES_ROTATE TRUE
J 2
(-6950 1800);
DISPLAY 0.489362 (-6950 1800);
PAINT GREEN (-6950 1800);
DISPLAY INVISIBLE (-6950 1800);
FORCEPROP 2 LAST VOLTAGE 6.3V
J 2
(-7300 1850);
DISPLAY 0.553191 (-7300 1850);
DISPLAY INVISIBLE (-7300 1850);
FORCEPROP 1 LAST MATERIAL X6S
J 2
(-6941 1879);
DISPLAY 0.574468 (-6941 1879);
PAINT GREEN (-6941 1879);
DISPLAY INVISIBLE (-6941 1879);
FORCEPROP 2 LAST PACK_TYPE C0201
J 2
(-7125 1850);
DISPLAY 0.553191 (-7125 1850);
DISPLAY INVISIBLE (-7125 1850);
FORCEPROP 2 LAST TOLERANCE 20%
J 2
(-7025 1850);
DISPLAY 0.553191 (-7025 1850);
DISPLAY INVISIBLE (-7025 1850);
FORCEPROP 1 LAST PATH I103
J 2
(-6950 1800);
DISPLAY 0.723404 (-6950 1800);
DISPLAY INVISIBLE (-6950 1800);
FORCEPROP 1 LAST PART_NUMBER SP_CH4221MEE01
J 2
(-7066 1888);
DISPLAY 0.574468 (-7066 1888);
PAINT GREEN (-7066 1888);
DISPLAY INVISIBLE (-7066 1888);
FORCEPROP 1 LAST LOCATION C6648
J 0
(-6700 1875);
DISPLAY 1.021277 (-6700 1875);
DISPLAY INVISIBLE (-6700 1875);
FORCEADD Q_CAP_DIFFBUS..2
R 2
(-6950 2000);
FORCEPROP 1 LAST LOCATION C6646
J 2
(-6675 2000);
DISPLAY 0.723404 (-6675 2000);
PAINT GREEN (-6675 2000);
FORCEPROP 2 LAST $SEC 1
J 2
(-6775 2075);
DISPLAY 0.680851 (-6775 2075);
PAINT MONO (-6775 2075);
DISPLAY INVISIBLE (-6775 2075);
FORCEPROP 2 LAST CDS_SEC 1
J 2
(-6775 2075);
DISPLAY 0.680851 (-6775 2075);
DISPLAY INVISIBLE (-6775 2075);
FORCEPROP 2 LASTPIN (-6875 2000) $PN 1
J 0
(-6865 2010);
DISPLAY 0.808511 (-6865 2010);
FORCEPROP 2 LASTPIN (-7025 2000) $PN 2
J 2
(-7035 2010);
DISPLAY 0.808511 (-7035 2010);
FORCEPROP 2 LAST VALUE DIFF BUS_0.22UF
J 2
(-7100 2000);
DISPLAY 0.553191 (-7100 2000);
FORCEPROP 1 LAST CDS_LMAN_SYM_OUTLINE -25,50,25,-50
J 2
(-6950 2000);
DISPLAY 0.468085 (-6950 2000);
PAINT GREEN (-6950 2000);
DISPLAY INVISIBLE (-6950 2000);
FORCEPROP 2 LAST CDS_LIB pure_quanta
J 2
(-6950 2000);
DISPLAY INVISIBLE (-6950 2000);
FORCEPROP 1 LAST PIN_NAMES_ROTATE TRUE
J 2
(-6950 2000);
DISPLAY 0.489362 (-6950 2000);
PAINT GREEN (-6950 2000);
DISPLAY INVISIBLE (-6950 2000);
FORCEPROP 2 LAST VOLTAGE 6.3V
J 2
(-7300 2050);
DISPLAY 0.553191 (-7300 2050);
DISPLAY INVISIBLE (-7300 2050);
FORCEPROP 1 LAST MATERIAL X6S
J 2
(-6941 2079);
DISPLAY 0.574468 (-6941 2079);
PAINT GREEN (-6941 2079);
DISPLAY INVISIBLE (-6941 2079);
FORCEPROP 2 LAST PACK_TYPE C0201
J 2
(-7125 2050);
DISPLAY 0.553191 (-7125 2050);
DISPLAY INVISIBLE (-7125 2050);
FORCEPROP 2 LAST TOLERANCE 20%
J 2
(-7025 2050);
DISPLAY 0.553191 (-7025 2050);
DISPLAY INVISIBLE (-7025 2050);
FORCEPROP 1 LAST PATH I104
J 2
(-6950 2000);
DISPLAY 0.723404 (-6950 2000);
DISPLAY INVISIBLE (-6950 2000);
FORCEPROP 1 LAST PART_NUMBER SP_CH4221MEE01
J 2
(-7066 2088);
DISPLAY 0.574468 (-7066 2088);
PAINT GREEN (-7066 2088);
DISPLAY INVISIBLE (-7066 2088);
FORCEPROP 1 LAST LOCATION C6646
J 0
(-6700 2075);
DISPLAY 1.021277 (-6700 2075);
DISPLAY INVISIBLE (-6700 2075);
FORCEADD Q_CAP_DIFFBUS..2
R 2
(-6950 2050);
FORCEPROP 1 LAST LOCATION C6645
J 2
(-6675 2050);
DISPLAY 0.723404 (-6675 2050);
PAINT GREEN (-6675 2050);
FORCEPROP 2 LAST $SEC 1
J 2
(-6775 2125);
DISPLAY 0.680851 (-6775 2125);
PAINT MONO (-6775 2125);
DISPLAY INVISIBLE (-6775 2125);
FORCEPROP 2 LAST CDS_SEC 1
J 2
(-6775 2125);
DISPLAY 0.680851 (-6775 2125);
DISPLAY INVISIBLE (-6775 2125);
FORCEPROP 2 LASTPIN (-6875 2050) $PN 1
J 0
(-6865 2060);
DISPLAY 0.808511 (-6865 2060);
FORCEPROP 2 LASTPIN (-7025 2050) $PN 2
J 2
(-7035 2060);
DISPLAY 0.808511 (-7035 2060);
FORCEPROP 2 LAST VOLTAGE 6.3V
J 2
(-6775 2200);
DISPLAY 0.553191 (-6775 2200);
PAINT GREEN (-6775 2200);
FORCEPROP 1 LAST MATERIAL X6S
J 2
(-7041 2254);
DISPLAY 0.574468 (-7041 2254);
PAINT GREEN (-7041 2254);
FORCEPROP 2 LAST TOLERANCE 20%
J 2
(-6900 2200);
DISPLAY 0.553191 (-6900 2200);
PAINT GREEN (-6900 2200);
FORCEPROP 2 LAST PACK_TYPE C0201
J 2
(-7000 2200);
DISPLAY 0.553191 (-7000 2200);
PAINT GREEN (-7000 2200);
FORCEPROP 2 LAST VALUE DIFF BUS_0.22UF
J 2
(-7100 2050);
DISPLAY 0.553191 (-7100 2050);
FORCEPROP 2 LAST CDS_LIB pure_quanta
J 2
(-6950 2050);
DISPLAY INVISIBLE (-6950 2050);
FORCEPROP 1 LAST CDS_LMAN_SYM_OUTLINE -25,50,25,-50
J 2
(-6950 2050);
DISPLAY 0.468085 (-6950 2050);
PAINT GREEN (-6950 2050);
DISPLAY INVISIBLE (-6950 2050);
FORCEPROP 1 LAST PIN_NAMES_ROTATE TRUE
J 2
(-6950 2050);
DISPLAY 0.489362 (-6950 2050);
PAINT GREEN (-6950 2050);
DISPLAY INVISIBLE (-6950 2050);
FORCEPROP 1 LAST PATH I105
J 2
(-6950 2050);
DISPLAY 0.723404 (-6950 2050);
DISPLAY INVISIBLE (-6950 2050);
FORCEPROP 1 LAST PART_NUMBER SP_CH4221MEE01
J 2
(-6766 2138);
DISPLAY 0.574468 (-6766 2138);
PAINT GREEN (-6766 2138);
DISPLAY INVISIBLE (-6766 2138);
FORCEPROP 1 LAST LOCATION C6645
J 0
(-6700 2125);
DISPLAY 1.021277 (-6700 2125);
DISPLAY INVISIBLE (-6700 2125);
FORCEADD TAP..1
(-6400 650);
FORCEPROP 3 LASTPIN (-6450 650) SIG_NAME P5E_CPU1_P0_TX_BUF_C_DP<15>
J 0
(-6440 660);
DISPLAY 0.659574 (-6440 660);
PAINT MONO (-6440 660);
DISPLAY INVISIBLE (-6440 660);
FORCEPROP 1 LASTPIN (-6450 650) BN 15
J 0
(-6462 658);
DISPLAY 0.680851 (-6462 658);
PAINT GREEN (-6462 658);
FORCEPROP 2 LAST CDS_LIB standard
J 0
(-6400 650);
DISPLAY INVISIBLE (-6400 650);
FORCEPROP 1 LAST BODY_TYPE PLUMBING
J 0
(-6400 700);
DISPLAY 0.872340 (-6400 700);
PAINT GREEN (-6400 700);
DISPLAY INVISIBLE (-6400 700);
FORCEPROP 1 LAST HDL_TAP TRUE
J 0
(-6075 525);
DISPLAY 0.872340 (-6075 525);
DISPLAY INVISIBLE (-6075 525);
FORCEPROP 1 LAST PATH I106
J 0
(-6402 650);
DISPLAY 0.872340 (-6402 650);
PAINT GREEN (-6402 650);
DISPLAY INVISIBLE (-6402 650);
FORCEADD TAP..1
(-6200 600);
FORCEPROP 3 LASTPIN (-6250 600) SIG_NAME P5E_CPU1_P0_TX_BUF_C_DN<15>
J 0
(-6240 610);
DISPLAY 0.659574 (-6240 610);
PAINT MONO (-6240 610);
DISPLAY INVISIBLE (-6240 610);
FORCEPROP 1 LASTPIN (-6250 600) BN 15
J 0
(-6262 608);
DISPLAY 0.680851 (-6262 608);
PAINT GREEN (-6262 608);
FORCEPROP 2 LAST CDS_LIB standard
J 0
(-6200 600);
DISPLAY INVISIBLE (-6200 600);
FORCEPROP 1 LAST BODY_TYPE PLUMBING
J 0
(-6200 650);
DISPLAY 0.872340 (-6200 650);
PAINT GREEN (-6200 650);
DISPLAY INVISIBLE (-6200 650);
FORCEPROP 1 LAST HDL_TAP TRUE
J 0
(-5875 475);
DISPLAY 0.872340 (-5875 475);
DISPLAY INVISIBLE (-5875 475);
FORCEPROP 1 LAST PATH I107
J 0
(-6202 600);
DISPLAY 0.872340 (-6202 600);
PAINT GREEN (-6202 600);
DISPLAY INVISIBLE (-6202 600);
FORCEADD TAP..1
(-6400 850);
FORCEPROP 3 LASTPIN (-6450 850) SIG_NAME P5E_CPU1_P0_TX_BUF_C_DP<14>
J 0
(-6440 860);
DISPLAY 0.659574 (-6440 860);
PAINT MONO (-6440 860);
DISPLAY INVISIBLE (-6440 860);
FORCEPROP 1 LASTPIN (-6450 850) BN 14
J 0
(-6462 858);
DISPLAY 0.680851 (-6462 858);
PAINT GREEN (-6462 858);
FORCEPROP 2 LAST CDS_LIB standard
J 0
(-6400 850);
DISPLAY INVISIBLE (-6400 850);
FORCEPROP 1 LAST BODY_TYPE PLUMBING
J 0
(-6400 900);
DISPLAY 0.872340 (-6400 900);
PAINT GREEN (-6400 900);
DISPLAY INVISIBLE (-6400 900);
FORCEPROP 1 LAST HDL_TAP TRUE
J 0
(-6075 725);
DISPLAY 0.872340 (-6075 725);
DISPLAY INVISIBLE (-6075 725);
FORCEPROP 1 LAST PATH I108
J 0
(-6402 850);
DISPLAY 0.872340 (-6402 850);
PAINT GREEN (-6402 850);
DISPLAY INVISIBLE (-6402 850);
FORCEADD TAP..1
(-6400 1050);
FORCEPROP 3 LASTPIN (-6450 1050) SIG_NAME P5E_CPU1_P0_TX_BUF_C_DP<13>
J 0
(-6440 1060);
DISPLAY 0.659574 (-6440 1060);
PAINT MONO (-6440 1060);
DISPLAY INVISIBLE (-6440 1060);
FORCEPROP 1 LASTPIN (-6450 1050) BN 13
J 0
(-6462 1058);
DISPLAY 0.680851 (-6462 1058);
PAINT GREEN (-6462 1058);
FORCEPROP 2 LAST CDS_LIB standard
J 0
(-6400 1050);
DISPLAY INVISIBLE (-6400 1050);
FORCEPROP 1 LAST BODY_TYPE PLUMBING
J 0
(-6400 1100);
DISPLAY 0.872340 (-6400 1100);
PAINT GREEN (-6400 1100);
DISPLAY INVISIBLE (-6400 1100);
FORCEPROP 1 LAST HDL_TAP TRUE
J 0
(-6075 925);
DISPLAY 0.872340 (-6075 925);
DISPLAY INVISIBLE (-6075 925);
FORCEPROP 1 LAST PATH I109
J 0
(-6402 1050);
DISPLAY 0.872340 (-6402 1050);
PAINT GREEN (-6402 1050);
DISPLAY INVISIBLE (-6402 1050);
FORCEADD TAP..1
R 2
(-3075 1025);
FORCEPROP 3 LASTPIN (-3025 1025) SIG_NAME P5E_CPU1_P0_TX_BUF_DP<5>
J 0
(-3015 1035);
DISPLAY 0.659574 (-3015 1035);
PAINT MONO (-3015 1035);
DISPLAY INVISIBLE (-3015 1035);
FORCEPROP 1 LASTPIN (-3025 1025) BN 5
J 2
(-3013 1033);
DISPLAY 0.680851 (-3013 1033);
PAINT GREEN (-3013 1033);
FORCEPROP 2 LAST CDS_LIB standard
J 0
(-3075 1025);
DISPLAY INVISIBLE (-3075 1025);
FORCEPROP 1 LAST BODY_TYPE PLUMBING
J 2
(-3075 1075);
DISPLAY 0.872340 (-3075 1075);
PAINT GREEN (-3075 1075);
DISPLAY INVISIBLE (-3075 1075);
FORCEPROP 1 LAST HDL_TAP TRUE
J 2
(-3400 900);
DISPLAY 0.872340 (-3400 900);
DISPLAY INVISIBLE (-3400 900);
FORCEPROP 1 LAST PATH I11
J 2
(-3073 1025);
DISPLAY 0.872340 (-3073 1025);
PAINT GREEN (-3073 1025);
DISPLAY INVISIBLE (-3073 1025);
FORCEADD TAP..1
(-6200 800);
FORCEPROP 3 LASTPIN (-6250 800) SIG_NAME P5E_CPU1_P0_TX_BUF_C_DN<14>
J 0
(-6240 810);
DISPLAY 0.659574 (-6240 810);
PAINT MONO (-6240 810);
DISPLAY INVISIBLE (-6240 810);
FORCEPROP 1 LASTPIN (-6250 800) BN 14
J 0
(-6262 808);
DISPLAY 0.680851 (-6262 808);
PAINT GREEN (-6262 808);
FORCEPROP 2 LAST CDS_LIB standard
J 0
(-6200 800);
DISPLAY INVISIBLE (-6200 800);
FORCEPROP 1 LAST BODY_TYPE PLUMBING
J 0
(-6200 850);
DISPLAY 0.872340 (-6200 850);
PAINT GREEN (-6200 850);
DISPLAY INVISIBLE (-6200 850);
FORCEPROP 1 LAST HDL_TAP TRUE
J 0
(-5875 675);
DISPLAY 0.872340 (-5875 675);
DISPLAY INVISIBLE (-5875 675);
FORCEPROP 1 LAST PATH I110
J 0
(-6202 800);
DISPLAY 0.872340 (-6202 800);
PAINT GREEN (-6202 800);
DISPLAY INVISIBLE (-6202 800);
FORCEADD TAP..1
(-6200 1000);
FORCEPROP 3 LASTPIN (-6250 1000) SIG_NAME P5E_CPU1_P0_TX_BUF_C_DN<13>
J 0
(-6240 1010);
DISPLAY 0.659574 (-6240 1010);
PAINT MONO (-6240 1010);
DISPLAY INVISIBLE (-6240 1010);
FORCEPROP 1 LASTPIN (-6250 1000) BN 13
J 0
(-6262 1008);
DISPLAY 0.680851 (-6262 1008);
PAINT GREEN (-6262 1008);
FORCEPROP 2 LAST CDS_LIB standard
J 0
(-6200 1000);
DISPLAY INVISIBLE (-6200 1000);
FORCEPROP 1 LAST BODY_TYPE PLUMBING
J 0
(-6200 1050);
DISPLAY 0.872340 (-6200 1050);
PAINT GREEN (-6200 1050);
DISPLAY INVISIBLE (-6200 1050);
FORCEPROP 1 LAST HDL_TAP TRUE
J 0
(-5875 875);
DISPLAY 0.872340 (-5875 875);
DISPLAY INVISIBLE (-5875 875);
FORCEPROP 1 LAST PATH I111
J 0
(-6202 1000);
DISPLAY 0.872340 (-6202 1000);
PAINT GREEN (-6202 1000);
DISPLAY INVISIBLE (-6202 1000);
FORCEADD TAP..1
(-6200 1200);
FORCEPROP 3 LASTPIN (-6250 1200) SIG_NAME P5E_CPU1_P0_TX_BUF_C_DN<12>
J 0
(-6240 1210);
DISPLAY 0.659574 (-6240 1210);
PAINT MONO (-6240 1210);
DISPLAY INVISIBLE (-6240 1210);
FORCEPROP 1 LASTPIN (-6250 1200) BN 12
J 0
(-6262 1208);
DISPLAY 0.680851 (-6262 1208);
PAINT GREEN (-6262 1208);
FORCEPROP 2 LAST CDS_LIB standard
J 0
(-6200 1200);
DISPLAY INVISIBLE (-6200 1200);
FORCEPROP 1 LAST BODY_TYPE PLUMBING
J 0
(-6200 1250);
DISPLAY 0.872340 (-6200 1250);
PAINT GREEN (-6200 1250);
DISPLAY INVISIBLE (-6200 1250);
FORCEPROP 1 LAST HDL_TAP TRUE
J 0
(-5875 1075);
DISPLAY 0.872340 (-5875 1075);
DISPLAY INVISIBLE (-5875 1075);
FORCEPROP 1 LAST PATH I112
J 0
(-6202 1200);
DISPLAY 0.872340 (-6202 1200);
PAINT GREEN (-6202 1200);
DISPLAY INVISIBLE (-6202 1200);
FORCEADD TAP..1
(-6400 1250);
FORCEPROP 3 LASTPIN (-6450 1250) SIG_NAME P5E_CPU1_P0_TX_BUF_C_DP<12>
J 0
(-6440 1260);
DISPLAY 0.659574 (-6440 1260);
PAINT MONO (-6440 1260);
DISPLAY INVISIBLE (-6440 1260);
FORCEPROP 1 LASTPIN (-6450 1250) BN 12
J 0
(-6462 1258);
DISPLAY 0.680851 (-6462 1258);
PAINT GREEN (-6462 1258);
FORCEPROP 2 LAST CDS_LIB standard
J 0
(-6400 1250);
DISPLAY INVISIBLE (-6400 1250);
FORCEPROP 1 LAST BODY_TYPE PLUMBING
J 0
(-6400 1300);
DISPLAY 0.872340 (-6400 1300);
PAINT GREEN (-6400 1300);
DISPLAY INVISIBLE (-6400 1300);
FORCEPROP 1 LAST HDL_TAP TRUE
J 0
(-6075 1125);
DISPLAY 0.872340 (-6075 1125);
DISPLAY INVISIBLE (-6075 1125);
FORCEPROP 1 LAST PATH I113
J 0
(-6402 1250);
DISPLAY 0.872340 (-6402 1250);
PAINT GREEN (-6402 1250);
DISPLAY INVISIBLE (-6402 1250);
FORCEADD TAP..1
(-6400 1450);
FORCEPROP 3 LASTPIN (-6450 1450) SIG_NAME P5E_CPU1_P0_TX_BUF_C_DP<11>
J 0
(-6440 1460);
DISPLAY 0.659574 (-6440 1460);
PAINT MONO (-6440 1460);
DISPLAY INVISIBLE (-6440 1460);
FORCEPROP 1 LASTPIN (-6450 1450) BN 11
J 0
(-6462 1458);
DISPLAY 0.680851 (-6462 1458);
PAINT GREEN (-6462 1458);
FORCEPROP 2 LAST CDS_LIB standard
J 0
(-6400 1450);
DISPLAY INVISIBLE (-6400 1450);
FORCEPROP 1 LAST BODY_TYPE PLUMBING
J 0
(-6400 1500);
DISPLAY 0.872340 (-6400 1500);
PAINT GREEN (-6400 1500);
DISPLAY INVISIBLE (-6400 1500);
FORCEPROP 1 LAST HDL_TAP TRUE
J 0
(-6075 1325);
DISPLAY 0.872340 (-6075 1325);
DISPLAY INVISIBLE (-6075 1325);
FORCEPROP 1 LAST PATH I114
J 0
(-6402 1450);
DISPLAY 0.872340 (-6402 1450);
PAINT GREEN (-6402 1450);
DISPLAY INVISIBLE (-6402 1450);
FORCEADD TAP..1
(-6400 1650);
FORCEPROP 3 LASTPIN (-6450 1650) SIG_NAME P5E_CPU1_P0_TX_BUF_C_DP<10>
J 0
(-6440 1660);
DISPLAY 0.659574 (-6440 1660);
PAINT MONO (-6440 1660);
DISPLAY INVISIBLE (-6440 1660);
FORCEPROP 1 LASTPIN (-6450 1650) BN 10
J 0
(-6462 1658);
DISPLAY 0.680851 (-6462 1658);
PAINT GREEN (-6462 1658);
FORCEPROP 2 LAST CDS_LIB standard
J 0
(-6400 1650);
DISPLAY INVISIBLE (-6400 1650);
FORCEPROP 1 LAST BODY_TYPE PLUMBING
J 0
(-6400 1700);
DISPLAY 0.872340 (-6400 1700);
PAINT GREEN (-6400 1700);
DISPLAY INVISIBLE (-6400 1700);
FORCEPROP 1 LAST HDL_TAP TRUE
J 0
(-6075 1525);
DISPLAY 0.872340 (-6075 1525);
DISPLAY INVISIBLE (-6075 1525);
FORCEPROP 1 LAST PATH I115
J 0
(-6402 1650);
DISPLAY 0.872340 (-6402 1650);
PAINT GREEN (-6402 1650);
DISPLAY INVISIBLE (-6402 1650);
FORCEADD TAP..1
(-6200 1400);
FORCEPROP 3 LASTPIN (-6250 1400) SIG_NAME P5E_CPU1_P0_TX_BUF_C_DN<11>
J 0
(-6240 1410);
DISPLAY 0.659574 (-6240 1410);
PAINT MONO (-6240 1410);
DISPLAY INVISIBLE (-6240 1410);
FORCEPROP 1 LASTPIN (-6250 1400) BN 11
J 0
(-6262 1408);
DISPLAY 0.680851 (-6262 1408);
PAINT GREEN (-6262 1408);
FORCEPROP 2 LAST CDS_LIB standard
J 0
(-6200 1400);
DISPLAY INVISIBLE (-6200 1400);
FORCEPROP 1 LAST BODY_TYPE PLUMBING
J 0
(-6200 1450);
DISPLAY 0.872340 (-6200 1450);
PAINT GREEN (-6200 1450);
DISPLAY INVISIBLE (-6200 1450);
FORCEPROP 1 LAST HDL_TAP TRUE
J 0
(-5875 1275);
DISPLAY 0.872340 (-5875 1275);
DISPLAY INVISIBLE (-5875 1275);
FORCEPROP 1 LAST PATH I116
J 0
(-6202 1400);
DISPLAY 0.872340 (-6202 1400);
PAINT GREEN (-6202 1400);
DISPLAY INVISIBLE (-6202 1400);
FORCEADD TAP..1
(-6200 1600);
FORCEPROP 3 LASTPIN (-6250 1600) SIG_NAME P5E_CPU1_P0_TX_BUF_C_DN<10>
J 0
(-6240 1610);
DISPLAY 0.659574 (-6240 1610);
PAINT MONO (-6240 1610);
DISPLAY INVISIBLE (-6240 1610);
FORCEPROP 1 LASTPIN (-6250 1600) BN 10
J 0
(-6262 1608);
DISPLAY 0.680851 (-6262 1608);
PAINT GREEN (-6262 1608);
FORCEPROP 2 LAST CDS_LIB standard
J 0
(-6200 1600);
DISPLAY INVISIBLE (-6200 1600);
FORCEPROP 1 LAST BODY_TYPE PLUMBING
J 0
(-6200 1650);
DISPLAY 0.872340 (-6200 1650);
PAINT GREEN (-6200 1650);
DISPLAY INVISIBLE (-6200 1650);
FORCEPROP 1 LAST HDL_TAP TRUE
J 0
(-5875 1475);
DISPLAY 0.872340 (-5875 1475);
DISPLAY INVISIBLE (-5875 1475);
FORCEPROP 1 LAST PATH I117
J 0
(-6202 1600);
DISPLAY 0.872340 (-6202 1600);
PAINT GREEN (-6202 1600);
DISPLAY INVISIBLE (-6202 1600);
FORCEADD TAP..1
(-6400 1850);
FORCEPROP 3 LASTPIN (-6450 1850) SIG_NAME P5E_CPU1_P0_TX_BUF_C_DP<9>
J 0
(-6440 1860);
DISPLAY 0.659574 (-6440 1860);
PAINT MONO (-6440 1860);
DISPLAY INVISIBLE (-6440 1860);
FORCEPROP 1 LASTPIN (-6450 1850) BN 9
J 0
(-6462 1858);
DISPLAY 0.680851 (-6462 1858);
PAINT GREEN (-6462 1858);
FORCEPROP 2 LAST CDS_LIB standard
J 0
(-6400 1850);
DISPLAY INVISIBLE (-6400 1850);
FORCEPROP 1 LAST BODY_TYPE PLUMBING
J 0
(-6400 1900);
DISPLAY 0.872340 (-6400 1900);
PAINT GREEN (-6400 1900);
DISPLAY INVISIBLE (-6400 1900);
FORCEPROP 1 LAST HDL_TAP TRUE
J 0
(-6075 1725);
DISPLAY 0.872340 (-6075 1725);
DISPLAY INVISIBLE (-6075 1725);
FORCEPROP 1 LAST PATH I118
J 0
(-6402 1850);
DISPLAY 0.872340 (-6402 1850);
PAINT GREEN (-6402 1850);
DISPLAY INVISIBLE (-6402 1850);
FORCEADD TAP..1
(-6400 2050);
FORCEPROP 3 LASTPIN (-6450 2050) SIG_NAME P5E_CPU1_P0_TX_BUF_C_DP<8>
J 0
(-6440 2060);
DISPLAY 0.659574 (-6440 2060);
PAINT MONO (-6440 2060);
DISPLAY INVISIBLE (-6440 2060);
FORCEPROP 1 LASTPIN (-6450 2050) BN 8
J 0
(-6462 2058);
DISPLAY 0.680851 (-6462 2058);
PAINT GREEN (-6462 2058);
FORCEPROP 2 LAST CDS_LIB standard
J 0
(-6400 2050);
DISPLAY INVISIBLE (-6400 2050);
FORCEPROP 1 LAST BODY_TYPE PLUMBING
J 0
(-6400 2100);
DISPLAY 0.872340 (-6400 2100);
PAINT GREEN (-6400 2100);
DISPLAY INVISIBLE (-6400 2100);
FORCEPROP 1 LAST HDL_TAP TRUE
J 0
(-6075 1925);
DISPLAY 0.872340 (-6075 1925);
DISPLAY INVISIBLE (-6075 1925);
FORCEPROP 1 LAST PATH I119
J 0
(-6402 2050);
DISPLAY 0.872340 (-6402 2050);
PAINT GREEN (-6402 2050);
DISPLAY INVISIBLE (-6402 2050);
FORCEADD TAP..1
R 2
(-3075 1225);
FORCEPROP 3 LASTPIN (-3025 1225) SIG_NAME P5E_CPU1_P0_TX_BUF_DP<4>
J 0
(-3015 1235);
DISPLAY 0.659574 (-3015 1235);
PAINT MONO (-3015 1235);
DISPLAY INVISIBLE (-3015 1235);
FORCEPROP 1 LASTPIN (-3025 1225) BN 4
J 2
(-3013 1233);
DISPLAY 0.680851 (-3013 1233);
PAINT GREEN (-3013 1233);
FORCEPROP 2 LAST CDS_LIB standard
J 0
(-3075 1225);
DISPLAY INVISIBLE (-3075 1225);
FORCEPROP 1 LAST BODY_TYPE PLUMBING
J 2
(-3075 1275);
DISPLAY 0.872340 (-3075 1275);
PAINT GREEN (-3075 1275);
DISPLAY INVISIBLE (-3075 1275);
FORCEPROP 1 LAST HDL_TAP TRUE
J 2
(-3400 1100);
DISPLAY 0.872340 (-3400 1100);
DISPLAY INVISIBLE (-3400 1100);
FORCEPROP 1 LAST PATH I12
J 2
(-3073 1225);
DISPLAY 0.872340 (-3073 1225);
PAINT GREEN (-3073 1225);
DISPLAY INVISIBLE (-3073 1225);
FORCEADD TAP..1
(-6200 1800);
FORCEPROP 3 LASTPIN (-6250 1800) SIG_NAME P5E_CPU1_P0_TX_BUF_C_DN<9>
J 0
(-6240 1810);
DISPLAY 0.659574 (-6240 1810);
PAINT MONO (-6240 1810);
DISPLAY INVISIBLE (-6240 1810);
FORCEPROP 1 LASTPIN (-6250 1800) BN 9
J 0
(-6262 1808);
DISPLAY 0.680851 (-6262 1808);
PAINT GREEN (-6262 1808);
FORCEPROP 2 LAST CDS_LIB standard
J 0
(-6200 1800);
DISPLAY INVISIBLE (-6200 1800);
FORCEPROP 1 LAST BODY_TYPE PLUMBING
J 0
(-6200 1850);
DISPLAY 0.872340 (-6200 1850);
PAINT GREEN (-6200 1850);
DISPLAY INVISIBLE (-6200 1850);
FORCEPROP 1 LAST HDL_TAP TRUE
J 0
(-5875 1675);
DISPLAY 0.872340 (-5875 1675);
DISPLAY INVISIBLE (-5875 1675);
FORCEPROP 1 LAST PATH I120
J 0
(-6202 1800);
DISPLAY 0.872340 (-6202 1800);
PAINT GREEN (-6202 1800);
DISPLAY INVISIBLE (-6202 1800);
FORCEADD TAP..1
(-6200 2000);
FORCEPROP 3 LASTPIN (-6250 2000) SIG_NAME P5E_CPU1_P0_TX_BUF_C_DN<8>
J 0
(-6240 2010);
DISPLAY 0.659574 (-6240 2010);
PAINT MONO (-6240 2010);
DISPLAY INVISIBLE (-6240 2010);
FORCEPROP 1 LASTPIN (-6250 2000) BN 8
J 0
(-6262 2008);
DISPLAY 0.680851 (-6262 2008);
PAINT GREEN (-6262 2008);
FORCEPROP 2 LAST CDS_LIB standard
J 0
(-6200 2000);
DISPLAY INVISIBLE (-6200 2000);
FORCEPROP 1 LAST BODY_TYPE PLUMBING
J 0
(-6200 2050);
DISPLAY 0.872340 (-6200 2050);
PAINT GREEN (-6200 2050);
DISPLAY INVISIBLE (-6200 2050);
FORCEPROP 1 LAST HDL_TAP TRUE
J 0
(-5875 1875);
DISPLAY 0.872340 (-5875 1875);
DISPLAY INVISIBLE (-5875 1875);
FORCEPROP 1 LAST PATH I121
J 0
(-6202 2000);
DISPLAY 0.872340 (-6202 2000);
PAINT GREEN (-6202 2000);
DISPLAY INVISIBLE (-6202 2000);
FORCEADD TAP..1
(-1800 3250);
FORCEPROP 3 LASTPIN (-1850 3250) SIG_NAME P5E_CPU1_P0_TX_BUF_DP<0>
J 0
(-1840 3260);
DISPLAY 0.659574 (-1840 3260);
PAINT MONO (-1840 3260);
DISPLAY INVISIBLE (-1840 3260);
FORCEPROP 1 LASTPIN (-1850 3250) BN 0
J 0
(-1862 3258);
DISPLAY 0.680851 (-1862 3258);
PAINT GREEN (-1862 3258);
FORCEPROP 2 LAST CDS_LIB standard
J 0
(-1800 3250);
DISPLAY INVISIBLE (-1800 3250);
FORCEPROP 1 LAST BODY_TYPE PLUMBING
J 0
(-1800 3300);
DISPLAY 0.872340 (-1800 3300);
PAINT GREEN (-1800 3300);
DISPLAY INVISIBLE (-1800 3300);
FORCEPROP 1 LAST HDL_TAP TRUE
J 0
(-1475 3125);
DISPLAY 0.872340 (-1475 3125);
DISPLAY INVISIBLE (-1475 3125);
FORCEPROP 1 LAST PATH I122
J 0
(-1802 3250);
DISPLAY 0.872340 (-1802 3250);
PAINT GREEN (-1802 3250);
DISPLAY INVISIBLE (-1802 3250);
FORCEADD TAP..1
(-1600 3150);
FORCEPROP 3 LASTPIN (-1650 3150) SIG_NAME P5E_CPU1_P0_TX_BUF_DN<0>
J 0
(-1640 3160);
DISPLAY 0.659574 (-1640 3160);
PAINT MONO (-1640 3160);
DISPLAY INVISIBLE (-1640 3160);
FORCEPROP 1 LASTPIN (-1650 3150) BN 0
J 0
(-1662 3158);
DISPLAY 0.680851 (-1662 3158);
PAINT GREEN (-1662 3158);
FORCEPROP 2 LAST CDS_LIB standard
J 0
(-1600 3150);
DISPLAY INVISIBLE (-1600 3150);
FORCEPROP 1 LAST BODY_TYPE PLUMBING
J 0
(-1600 3200);
DISPLAY 0.872340 (-1600 3200);
PAINT GREEN (-1600 3200);
DISPLAY INVISIBLE (-1600 3200);
FORCEPROP 1 LAST HDL_TAP TRUE
J 0
(-1275 3025);
DISPLAY 0.872340 (-1275 3025);
DISPLAY INVISIBLE (-1275 3025);
FORCEPROP 1 LAST PATH I123
J 0
(-1602 3150);
DISPLAY 0.872340 (-1602 3150);
PAINT GREEN (-1602 3150);
DISPLAY INVISIBLE (-1602 3150);
FORCEADD TAP..1
(-1800 3600);
FORCEPROP 3 LASTPIN (-1850 3600) SIG_NAME P5E_CPU1_P0_TX_BUF_DP<1>
J 0
(-1840 3610);
DISPLAY 0.659574 (-1840 3610);
PAINT MONO (-1840 3610);
DISPLAY INVISIBLE (-1840 3610);
FORCEPROP 1 LASTPIN (-1850 3600) BN 1
J 0
(-1862 3608);
DISPLAY 0.680851 (-1862 3608);
PAINT GREEN (-1862 3608);
FORCEPROP 2 LAST CDS_LIB standard
J 0
(-1800 3600);
DISPLAY INVISIBLE (-1800 3600);
FORCEPROP 1 LAST BODY_TYPE PLUMBING
J 0
(-1800 3650);
DISPLAY 0.872340 (-1800 3650);
PAINT GREEN (-1800 3650);
DISPLAY INVISIBLE (-1800 3650);
FORCEPROP 1 LAST HDL_TAP TRUE
J 0
(-1475 3475);
DISPLAY 0.872340 (-1475 3475);
DISPLAY INVISIBLE (-1475 3475);
FORCEPROP 1 LAST PATH I124
J 0
(-1802 3600);
DISPLAY 0.872340 (-1802 3600);
PAINT GREEN (-1802 3600);
DISPLAY INVISIBLE (-1802 3600);
FORCEADD TAP..1
(-1600 3500);
FORCEPROP 3 LASTPIN (-1650 3500) SIG_NAME P5E_CPU1_P0_TX_BUF_DN<1>
J 0
(-1640 3510);
DISPLAY 0.659574 (-1640 3510);
PAINT MONO (-1640 3510);
DISPLAY INVISIBLE (-1640 3510);
FORCEPROP 1 LASTPIN (-1650 3500) BN 1
J 0
(-1662 3508);
DISPLAY 0.680851 (-1662 3508);
PAINT GREEN (-1662 3508);
FORCEPROP 2 LAST CDS_LIB standard
J 0
(-1600 3500);
DISPLAY INVISIBLE (-1600 3500);
FORCEPROP 1 LAST BODY_TYPE PLUMBING
J 0
(-1600 3550);
DISPLAY 0.872340 (-1600 3550);
PAINT GREEN (-1600 3550);
DISPLAY INVISIBLE (-1600 3550);
FORCEPROP 1 LAST HDL_TAP TRUE
J 0
(-1275 3375);
DISPLAY 0.872340 (-1275 3375);
DISPLAY INVISIBLE (-1275 3375);
FORCEPROP 1 LAST PATH I125
J 0
(-1602 3500);
DISPLAY 0.872340 (-1602 3500);
PAINT GREEN (-1602 3500);
DISPLAY INVISIBLE (-1602 3500);
FORCEADD OFFPAGE..2
(-5200 2025);
FORCEPROP 2 LAST $XR0 121 
J 0
(-5011 2025);
DISPLAY 0.638298 (-5011 2025);
PAINT MONO (-5011 2025);
FORCEPROP 2 LAST CDS_LIB standard
J 0
(-5200 2025);
DISPLAY INVISIBLE (-5200 2025);
FORCEPROP 1 LAST OFFPAGE TRUE
J 0
(-4875 1900);
DISPLAY 0.872340 (-4875 1900);
DISPLAY INVISIBLE (-4875 1900);
FORCEPROP 1 LAST COMMENT_BODY TRUE
J 0
(-5245 1930);
DISPLAY 0.872340 (-5245 1930);
PAINT GREEN (-5245 1930);
DISPLAY INVISIBLE (-5245 1930);
FORCEPROP 2 LAST PATH I126
J 0
(-5000 2075);
DISPLAY 0.680851 (-5000 2075);
DISPLAY INVISIBLE (-5000 2075);
FORCEADD OFFPAGE..2
(-5200 2075);
FORCEPROP 2 LAST $XR0 121 
J 0
(-5011 2075);
DISPLAY 0.638298 (-5011 2075);
PAINT MONO (-5011 2075);
FORCEPROP 2 LAST CDS_LIB standard
J 0
(-5200 2075);
DISPLAY INVISIBLE (-5200 2075);
FORCEPROP 1 LAST OFFPAGE TRUE
J 0
(-4875 1950);
DISPLAY 0.872340 (-4875 1950);
DISPLAY INVISIBLE (-4875 1950);
FORCEPROP 1 LAST COMMENT_BODY TRUE
J 0
(-5245 1980);
DISPLAY 0.872340 (-5245 1980);
PAINT GREEN (-5245 1980);
DISPLAY INVISIBLE (-5245 1980);
FORCEPROP 2 LAST PATH I127
J 0
(-5000 2125);
DISPLAY 0.680851 (-5000 2125);
DISPLAY INVISIBLE (-5000 2125);
FORCEADD TAP..1
(-1800 3950);
FORCEPROP 3 LASTPIN (-1850 3950) SIG_NAME P5E_CPU1_P0_TX_BUF_DP<2>
J 0
(-1840 3960);
DISPLAY 0.659574 (-1840 3960);
PAINT MONO (-1840 3960);
DISPLAY INVISIBLE (-1840 3960);
FORCEPROP 1 LASTPIN (-1850 3950) BN 2
J 0
(-1862 3958);
DISPLAY 0.680851 (-1862 3958);
PAINT GREEN (-1862 3958);
FORCEPROP 2 LAST CDS_LIB standard
J 0
(-1800 3950);
DISPLAY INVISIBLE (-1800 3950);
FORCEPROP 1 LAST BODY_TYPE PLUMBING
J 0
(-1800 4000);
DISPLAY 0.872340 (-1800 4000);
PAINT GREEN (-1800 4000);
DISPLAY INVISIBLE (-1800 4000);
FORCEPROP 1 LAST HDL_TAP TRUE
J 0
(-1475 3825);
DISPLAY 0.872340 (-1475 3825);
DISPLAY INVISIBLE (-1475 3825);
FORCEPROP 1 LAST PATH I128
J 0
(-1802 3950);
DISPLAY 0.872340 (-1802 3950);
PAINT GREEN (-1802 3950);
DISPLAY INVISIBLE (-1802 3950);
FORCEADD TAP..1
(-1600 3850);
FORCEPROP 3 LASTPIN (-1650 3850) SIG_NAME P5E_CPU1_P0_TX_BUF_DN<2>
J 0
(-1640 3860);
DISPLAY 0.659574 (-1640 3860);
PAINT MONO (-1640 3860);
DISPLAY INVISIBLE (-1640 3860);
FORCEPROP 1 LASTPIN (-1650 3850) BN 2
J 0
(-1662 3858);
DISPLAY 0.680851 (-1662 3858);
PAINT GREEN (-1662 3858);
FORCEPROP 2 LAST CDS_LIB standard
J 0
(-1600 3850);
DISPLAY INVISIBLE (-1600 3850);
FORCEPROP 1 LAST BODY_TYPE PLUMBING
J 0
(-1600 3900);
DISPLAY 0.872340 (-1600 3900);
PAINT GREEN (-1600 3900);
DISPLAY INVISIBLE (-1600 3900);
FORCEPROP 1 LAST HDL_TAP TRUE
J 0
(-1275 3725);
DISPLAY 0.872340 (-1275 3725);
DISPLAY INVISIBLE (-1275 3725);
FORCEPROP 1 LAST PATH I129
J 0
(-1602 3850);
DISPLAY 0.872340 (-1602 3850);
PAINT GREEN (-1602 3850);
DISPLAY INVISIBLE (-1602 3850);
FORCEADD TAP..1
R 2
(-3075 1425);
FORCEPROP 3 LASTPIN (-3025 1425) SIG_NAME P5E_CPU1_P0_TX_BUF_DP<3>
J 0
(-3015 1435);
DISPLAY 0.659574 (-3015 1435);
PAINT MONO (-3015 1435);
DISPLAY INVISIBLE (-3015 1435);
FORCEPROP 1 LASTPIN (-3025 1425) BN 3
J 2
(-3013 1433);
DISPLAY 0.680851 (-3013 1433);
PAINT GREEN (-3013 1433);
FORCEPROP 2 LAST CDS_LIB standard
J 0
(-3075 1425);
DISPLAY INVISIBLE (-3075 1425);
FORCEPROP 1 LAST BODY_TYPE PLUMBING
J 2
(-3075 1475);
DISPLAY 0.872340 (-3075 1475);
PAINT GREEN (-3075 1475);
DISPLAY INVISIBLE (-3075 1475);
FORCEPROP 1 LAST HDL_TAP TRUE
J 2
(-3400 1300);
DISPLAY 0.872340 (-3400 1300);
DISPLAY INVISIBLE (-3400 1300);
FORCEPROP 1 LAST PATH I13
J 2
(-3073 1425);
DISPLAY 0.872340 (-3073 1425);
PAINT GREEN (-3073 1425);
DISPLAY INVISIBLE (-3073 1425);
FORCEADD TAP..1
(-1600 4200);
FORCEPROP 3 LASTPIN (-1650 4200) SIG_NAME P5E_CPU1_P0_TX_BUF_DN<3>
J 0
(-1640 4210);
DISPLAY 0.659574 (-1640 4210);
PAINT MONO (-1640 4210);
DISPLAY INVISIBLE (-1640 4210);
FORCEPROP 1 LASTPIN (-1650 4200) BN 3
J 0
(-1662 4208);
DISPLAY 0.680851 (-1662 4208);
PAINT GREEN (-1662 4208);
FORCEPROP 2 LAST CDS_LIB standard
J 0
(-1600 4200);
DISPLAY INVISIBLE (-1600 4200);
FORCEPROP 1 LAST BODY_TYPE PLUMBING
J 0
(-1600 4250);
DISPLAY 0.872340 (-1600 4250);
PAINT GREEN (-1600 4250);
DISPLAY INVISIBLE (-1600 4250);
FORCEPROP 1 LAST HDL_TAP TRUE
J 0
(-1275 4075);
DISPLAY 0.872340 (-1275 4075);
DISPLAY INVISIBLE (-1275 4075);
FORCEPROP 1 LAST PATH I130
J 0
(-1602 4200);
DISPLAY 0.872340 (-1602 4200);
PAINT GREEN (-1602 4200);
DISPLAY INVISIBLE (-1602 4200);
FORCEADD TAP..1
(-1800 4300);
FORCEPROP 3 LASTPIN (-1850 4300) SIG_NAME P5E_CPU1_P0_TX_BUF_DP<3>
J 0
(-1840 4310);
DISPLAY 0.659574 (-1840 4310);
PAINT MONO (-1840 4310);
DISPLAY INVISIBLE (-1840 4310);
FORCEPROP 1 LASTPIN (-1850 4300) BN 3
J 0
(-1862 4308);
DISPLAY 0.680851 (-1862 4308);
PAINT GREEN (-1862 4308);
FORCEPROP 2 LAST CDS_LIB standard
J 0
(-1800 4300);
DISPLAY INVISIBLE (-1800 4300);
FORCEPROP 1 LAST BODY_TYPE PLUMBING
J 0
(-1800 4350);
DISPLAY 0.872340 (-1800 4350);
PAINT GREEN (-1800 4350);
DISPLAY INVISIBLE (-1800 4350);
FORCEPROP 1 LAST HDL_TAP TRUE
J 0
(-1475 4175);
DISPLAY 0.872340 (-1475 4175);
DISPLAY INVISIBLE (-1475 4175);
FORCEPROP 1 LAST PATH I131
J 0
(-1802 4300);
DISPLAY 0.872340 (-1802 4300);
PAINT GREEN (-1802 4300);
DISPLAY INVISIBLE (-1802 4300);
FORCEADD TAP..1
(-1800 4650);
FORCEPROP 3 LASTPIN (-1850 4650) SIG_NAME P5E_CPU1_P0_TX_BUF_DP<4>
J 0
(-1840 4660);
DISPLAY 0.659574 (-1840 4660);
PAINT MONO (-1840 4660);
DISPLAY INVISIBLE (-1840 4660);
FORCEPROP 1 LASTPIN (-1850 4650) BN 4
J 0
(-1862 4658);
DISPLAY 0.680851 (-1862 4658);
PAINT GREEN (-1862 4658);
FORCEPROP 2 LAST CDS_LIB standard
J 0
(-1800 4650);
DISPLAY INVISIBLE (-1800 4650);
FORCEPROP 1 LAST BODY_TYPE PLUMBING
J 0
(-1800 4700);
DISPLAY 0.872340 (-1800 4700);
PAINT GREEN (-1800 4700);
DISPLAY INVISIBLE (-1800 4700);
FORCEPROP 1 LAST HDL_TAP TRUE
J 0
(-1475 4525);
DISPLAY 0.872340 (-1475 4525);
DISPLAY INVISIBLE (-1475 4525);
FORCEPROP 1 LAST PATH I132
J 0
(-1802 4650);
DISPLAY 0.872340 (-1802 4650);
PAINT GREEN (-1802 4650);
DISPLAY INVISIBLE (-1802 4650);
FORCEADD TAP..1
(-1600 4550);
FORCEPROP 3 LASTPIN (-1650 4550) SIG_NAME P5E_CPU1_P0_TX_BUF_DN<4>
J 0
(-1640 4560);
DISPLAY 0.659574 (-1640 4560);
PAINT MONO (-1640 4560);
DISPLAY INVISIBLE (-1640 4560);
FORCEPROP 1 LASTPIN (-1650 4550) BN 4
J 0
(-1662 4558);
DISPLAY 0.680851 (-1662 4558);
PAINT GREEN (-1662 4558);
FORCEPROP 2 LAST CDS_LIB standard
J 0
(-1600 4550);
DISPLAY INVISIBLE (-1600 4550);
FORCEPROP 1 LAST BODY_TYPE PLUMBING
J 0
(-1600 4600);
DISPLAY 0.872340 (-1600 4600);
PAINT GREEN (-1600 4600);
DISPLAY INVISIBLE (-1600 4600);
FORCEPROP 1 LAST HDL_TAP TRUE
J 0
(-1275 4425);
DISPLAY 0.872340 (-1275 4425);
DISPLAY INVISIBLE (-1275 4425);
FORCEPROP 1 LAST PATH I133
J 0
(-1602 4550);
DISPLAY 0.872340 (-1602 4550);
PAINT GREEN (-1602 4550);
DISPLAY INVISIBLE (-1602 4550);
FORCEADD TAP..1
(-1800 5000);
FORCEPROP 3 LASTPIN (-1850 5000) SIG_NAME P5E_CPU1_P0_TX_BUF_DP<5>
J 0
(-1840 5010);
DISPLAY 0.659574 (-1840 5010);
PAINT MONO (-1840 5010);
DISPLAY INVISIBLE (-1840 5010);
FORCEPROP 1 LASTPIN (-1850 5000) BN 5
J 0
(-1862 5008);
DISPLAY 0.680851 (-1862 5008);
PAINT GREEN (-1862 5008);
FORCEPROP 2 LAST CDS_LIB standard
J 0
(-1800 5000);
DISPLAY INVISIBLE (-1800 5000);
FORCEPROP 1 LAST BODY_TYPE PLUMBING
J 0
(-1800 5050);
DISPLAY 0.872340 (-1800 5050);
PAINT GREEN (-1800 5050);
DISPLAY INVISIBLE (-1800 5050);
FORCEPROP 1 LAST HDL_TAP TRUE
J 0
(-1475 4875);
DISPLAY 0.872340 (-1475 4875);
DISPLAY INVISIBLE (-1475 4875);
FORCEPROP 1 LAST PATH I134
J 0
(-1802 5000);
DISPLAY 0.872340 (-1802 5000);
PAINT GREEN (-1802 5000);
DISPLAY INVISIBLE (-1802 5000);
FORCEADD TAP..1
(-1600 4900);
FORCEPROP 3 LASTPIN (-1650 4900) SIG_NAME P5E_CPU1_P0_TX_BUF_DN<5>
J 0
(-1640 4910);
DISPLAY 0.659574 (-1640 4910);
PAINT MONO (-1640 4910);
DISPLAY INVISIBLE (-1640 4910);
FORCEPROP 1 LASTPIN (-1650 4900) BN 5
J 0
(-1662 4908);
DISPLAY 0.680851 (-1662 4908);
PAINT GREEN (-1662 4908);
FORCEPROP 2 LAST CDS_LIB standard
J 0
(-1600 4900);
DISPLAY INVISIBLE (-1600 4900);
FORCEPROP 1 LAST BODY_TYPE PLUMBING
J 0
(-1600 4950);
DISPLAY 0.872340 (-1600 4950);
PAINT GREEN (-1600 4950);
DISPLAY INVISIBLE (-1600 4950);
FORCEPROP 1 LAST HDL_TAP TRUE
J 0
(-1275 4775);
DISPLAY 0.872340 (-1275 4775);
DISPLAY INVISIBLE (-1275 4775);
FORCEPROP 1 LAST PATH I135
J 0
(-1602 4900);
DISPLAY 0.872340 (-1602 4900);
PAINT GREEN (-1602 4900);
DISPLAY INVISIBLE (-1602 4900);
FORCEADD TAP..1
(-1600 5250);
FORCEPROP 3 LASTPIN (-1650 5250) SIG_NAME P5E_CPU1_P0_TX_BUF_DN<6>
J 0
(-1640 5260);
DISPLAY 0.659574 (-1640 5260);
PAINT MONO (-1640 5260);
DISPLAY INVISIBLE (-1640 5260);
FORCEPROP 1 LASTPIN (-1650 5250) BN 6
J 0
(-1662 5258);
DISPLAY 0.680851 (-1662 5258);
PAINT GREEN (-1662 5258);
FORCEPROP 2 LAST CDS_LIB standard
J 0
(-1600 5250);
DISPLAY INVISIBLE (-1600 5250);
FORCEPROP 1 LAST BODY_TYPE PLUMBING
J 0
(-1600 5300);
DISPLAY 0.872340 (-1600 5300);
PAINT GREEN (-1600 5300);
DISPLAY INVISIBLE (-1600 5300);
FORCEPROP 1 LAST HDL_TAP TRUE
J 0
(-1275 5125);
DISPLAY 0.872340 (-1275 5125);
DISPLAY INVISIBLE (-1275 5125);
FORCEPROP 1 LAST PATH I136
J 0
(-1602 5250);
DISPLAY 0.872340 (-1602 5250);
PAINT GREEN (-1602 5250);
DISPLAY INVISIBLE (-1602 5250);
FORCEADD TAP..1
(-1800 5350);
FORCEPROP 3 LASTPIN (-1850 5350) SIG_NAME P5E_CPU1_P0_TX_BUF_DP<6>
J 0
(-1840 5360);
DISPLAY 0.659574 (-1840 5360);
PAINT MONO (-1840 5360);
DISPLAY INVISIBLE (-1840 5360);
FORCEPROP 1 LASTPIN (-1850 5350) BN 6
J 0
(-1862 5358);
DISPLAY 0.680851 (-1862 5358);
PAINT GREEN (-1862 5358);
FORCEPROP 2 LAST CDS_LIB standard
J 0
(-1800 5350);
DISPLAY INVISIBLE (-1800 5350);
FORCEPROP 1 LAST BODY_TYPE PLUMBING
J 0
(-1800 5400);
DISPLAY 0.872340 (-1800 5400);
PAINT GREEN (-1800 5400);
DISPLAY INVISIBLE (-1800 5400);
FORCEPROP 1 LAST HDL_TAP TRUE
J 0
(-1475 5225);
DISPLAY 0.872340 (-1475 5225);
DISPLAY INVISIBLE (-1475 5225);
FORCEPROP 1 LAST PATH I137
J 0
(-1802 5350);
DISPLAY 0.872340 (-1802 5350);
PAINT GREEN (-1802 5350);
DISPLAY INVISIBLE (-1802 5350);
FORCEADD TAP..1
(-1800 5700);
FORCEPROP 3 LASTPIN (-1850 5700) SIG_NAME P5E_CPU1_P0_TX_BUF_DP<7>
J 0
(-1840 5710);
DISPLAY 0.659574 (-1840 5710);
PAINT MONO (-1840 5710);
DISPLAY INVISIBLE (-1840 5710);
FORCEPROP 1 LASTPIN (-1850 5700) BN 7
J 0
(-1862 5708);
DISPLAY 0.680851 (-1862 5708);
PAINT GREEN (-1862 5708);
FORCEPROP 2 LAST CDS_LIB standard
J 0
(-1800 5700);
DISPLAY INVISIBLE (-1800 5700);
FORCEPROP 1 LAST BODY_TYPE PLUMBING
J 0
(-1800 5750);
DISPLAY 0.872340 (-1800 5750);
PAINT GREEN (-1800 5750);
DISPLAY INVISIBLE (-1800 5750);
FORCEPROP 1 LAST HDL_TAP TRUE
J 0
(-1475 5575);
DISPLAY 0.872340 (-1475 5575);
DISPLAY INVISIBLE (-1475 5575);
FORCEPROP 1 LAST PATH I138
J 0
(-1802 5700);
DISPLAY 0.872340 (-1802 5700);
PAINT GREEN (-1802 5700);
DISPLAY INVISIBLE (-1802 5700);
FORCEADD TAP..1
(-1600 5600);
FORCEPROP 3 LASTPIN (-1650 5600) SIG_NAME P5E_CPU1_P0_TX_BUF_DN<7>
J 0
(-1640 5610);
DISPLAY 0.659574 (-1640 5610);
PAINT MONO (-1640 5610);
DISPLAY INVISIBLE (-1640 5610);
FORCEPROP 1 LASTPIN (-1650 5600) BN 7
J 0
(-1662 5608);
DISPLAY 0.680851 (-1662 5608);
PAINT GREEN (-1662 5608);
FORCEPROP 2 LAST CDS_LIB standard
J 0
(-1600 5600);
DISPLAY INVISIBLE (-1600 5600);
FORCEPROP 1 LAST BODY_TYPE PLUMBING
J 0
(-1600 5650);
DISPLAY 0.872340 (-1600 5650);
PAINT GREEN (-1600 5650);
DISPLAY INVISIBLE (-1600 5650);
FORCEPROP 1 LAST HDL_TAP TRUE
J 0
(-1275 5475);
DISPLAY 0.872340 (-1275 5475);
DISPLAY INVISIBLE (-1275 5475);
FORCEPROP 1 LAST PATH I139
J 0
(-1602 5600);
DISPLAY 0.872340 (-1602 5600);
PAINT GREEN (-1602 5600);
DISPLAY INVISIBLE (-1602 5600);
FORCEADD TAP..1
R 2
(-3075 1625);
FORCEPROP 3 LASTPIN (-3025 1625) SIG_NAME P5E_CPU1_P0_TX_BUF_DP<2>
J 0
(-3015 1635);
DISPLAY 0.659574 (-3015 1635);
PAINT MONO (-3015 1635);
DISPLAY INVISIBLE (-3015 1635);
FORCEPROP 1 LASTPIN (-3025 1625) BN 2
J 2
(-3013 1633);
DISPLAY 0.680851 (-3013 1633);
PAINT GREEN (-3013 1633);
FORCEPROP 2 LAST CDS_LIB standard
J 0
(-3075 1625);
DISPLAY INVISIBLE (-3075 1625);
FORCEPROP 1 LAST BODY_TYPE PLUMBING
J 2
(-3075 1675);
DISPLAY 0.872340 (-3075 1675);
PAINT GREEN (-3075 1675);
DISPLAY INVISIBLE (-3075 1675);
FORCEPROP 1 LAST HDL_TAP TRUE
J 2
(-3400 1500);
DISPLAY 0.872340 (-3400 1500);
DISPLAY INVISIBLE (-3400 1500);
FORCEPROP 1 LAST PATH I14
J 2
(-3073 1625);
DISPLAY 0.872340 (-3073 1625);
PAINT GREEN (-3073 1625);
DISPLAY INVISIBLE (-3073 1625);
FORCEADD OFFPAGE..5
R 2
(-625 5625);
FORCEPROP 2 LAST $XR0 320 
J 0
(-436 5625);
DISPLAY 0.638298 (-436 5625);
PAINT MONO (-436 5625);
FORCEPROP 2 LAST CDS_LIB standard
J 0
(-625 5625);
DISPLAY INVISIBLE (-625 5625);
FORCEPROP 1 LAST OFFPAGE TRUE
J 2
(-950 5500);
DISPLAY 0.872340 (-950 5500);
PAINT GREEN (-950 5500);
DISPLAY INVISIBLE (-950 5500);
FORCEPROP 1 LAST COMMENT_BODY TRUE
J 2
(-725 5550);
DISPLAY 0.872340 (-725 5550);
PAINT GREEN (-725 5550);
DISPLAY INVISIBLE (-725 5550);
FORCEPROP 2 LAST PATH I140
J 0
(-450 5700);
DISPLAY 0.680851 (-450 5700);
DISPLAY INVISIBLE (-450 5700);
FORCEADD OFFPAGE..5
R 2
(-600 5725);
FORCEPROP 2 LAST $XR0 320 
J 0
(-411 5725);
DISPLAY 0.638298 (-411 5725);
PAINT MONO (-411 5725);
FORCEPROP 2 LAST CDS_LIB standard
J 0
(-600 5725);
DISPLAY INVISIBLE (-600 5725);
FORCEPROP 1 LAST OFFPAGE TRUE
J 2
(-925 5600);
DISPLAY 0.872340 (-925 5600);
PAINT GREEN (-925 5600);
DISPLAY INVISIBLE (-925 5600);
FORCEPROP 1 LAST COMMENT_BODY TRUE
J 2
(-700 5650);
DISPLAY 0.872340 (-700 5650);
PAINT GREEN (-700 5650);
DISPLAY INVISIBLE (-700 5650);
FORCEPROP 2 LAST PATH I141
J 0
(-425 5800);
DISPLAY 0.680851 (-425 5800);
DISPLAY INVISIBLE (-425 5800);
FORCEADD PT5161LRS..11
(-2525 4450);
FORCEPROP 1 LAST LOCATION U6014
J 0
(-2875 6075);
DISPLAY 0.723404 (-2875 6075);
PAINT GREEN (-2875 6075);
FORCEPROP 0 LAST $SEC 11
J 0
(-2875 6225);
DISPLAY 0.680851 (-2875 6225);
PAINT MONO (-2875 6225);
DISPLAY INVISIBLE (-2875 6225);
FORCEPROP 0 LAST CDS_SEC 11
J 0
(-2875 6225);
DISPLAY 0.680851 (-2875 6225);
DISPLAY INVISIBLE (-2875 6225);
FORCEPROP 0 LASTPIN (-2075 5600) $PN CK10
J 0
(-2065 5610);
DISPLAY 0.680851 (-2065 5610);
PAINT MONO (-2065 5610);
FORCEPROP 0 LASTPIN (-2075 5250) $PN CU10
J 0
(-2065 5260);
DISPLAY 0.680851 (-2065 5260);
PAINT MONO (-2065 5260);
FORCEPROP 0 LASTPIN (-2075 4900) $PN DD10
J 0
(-2065 4910);
DISPLAY 0.680851 (-2065 4910);
PAINT MONO (-2065 4910);
FORCEPROP 0 LASTPIN (-2075 4550) $PN DL10
J 0
(-2065 4560);
DISPLAY 0.680851 (-2065 4560);
PAINT MONO (-2065 4560);
FORCEPROP 0 LASTPIN (-2075 4200) $PN DV10
J 0
(-2065 4210);
DISPLAY 0.680851 (-2065 4210);
PAINT MONO (-2065 4210);
FORCEPROP 0 LASTPIN (-2075 3850) $PN EE10
J 0
(-2065 3860);
DISPLAY 0.680851 (-2065 3860);
PAINT MONO (-2065 3860);
FORCEPROP 0 LASTPIN (-2075 3500) $PN EM10
J 0
(-2065 3510);
DISPLAY 0.680851 (-2065 3510);
PAINT MONO (-2065 3510);
FORCEPROP 0 LASTPIN (-2075 3150) $PN EW10
J 0
(-2065 3160);
DISPLAY 0.680851 (-2065 3160);
PAINT MONO (-2065 3160);
FORCEPROP 0 LASTPIN (-2075 5700) $PN CH7
J 0
(-2065 5710);
DISPLAY 0.680851 (-2065 5710);
PAINT MONO (-2065 5710);
FORCEPROP 0 LASTPIN (-2075 5350) $PN CR7
J 0
(-2065 5360);
DISPLAY 0.680851 (-2065 5360);
PAINT MONO (-2065 5360);
FORCEPROP 0 LASTPIN (-2075 5000) $PN DB7
J 0
(-2065 5010);
DISPLAY 0.680851 (-2065 5010);
PAINT MONO (-2065 5010);
FORCEPROP 0 LASTPIN (-2075 4650) $PN DJ7
J 0
(-2065 4660);
DISPLAY 0.680851 (-2065 4660);
PAINT MONO (-2065 4660);
FORCEPROP 0 LASTPIN (-2075 4300) $PN DT7
J 0
(-2065 4310);
DISPLAY 0.680851 (-2065 4310);
PAINT MONO (-2065 4310);
FORCEPROP 0 LASTPIN (-2075 3950) $PN EC7
J 0
(-2065 3960);
DISPLAY 0.680851 (-2065 3960);
PAINT MONO (-2065 3960);
FORCEPROP 0 LASTPIN (-2075 3600) $PN EK7
J 0
(-2065 3610);
DISPLAY 0.680851 (-2065 3610);
PAINT MONO (-2065 3610);
FORCEPROP 0 LASTPIN (-2075 3250) $PN EU7
J 0
(-2065 3260);
DISPLAY 0.680851 (-2065 3260);
PAINT MONO (-2065 3260);
FORCEPROP 2 LAST PART_TYPE SMLF
J 0
(-2875 6175);
DISPLAY 0.680851 (-2875 6175);
FORCEPROP 2 LAST VALUE PT5161LRS
J 0
(-2875 6125);
DISPLAY 0.680851 (-2875 6125);
FORCEPROP 1 LAST MATERIAL IC
J 0
(-2875 5925);
DISPLAY 0.723404 (-2875 5925);
PAINT GREEN (-2875 5925);
FORCEPROP 2 LAST CDS_LIB pure_quanta
J 0
(-2525 4450);
DISPLAY INVISIBLE (-2525 4450);
FORCEPROP 1 LAST CDS_LMAN_SYM_OUTLINE -350,1450,300,-1400
J 0
(-2525 4450);
DISPLAY 0.468085 (-2525 4450);
PAINT GREEN (-2525 4450);
DISPLAY INVISIBLE (-2525 4450);
FORCEPROP 1 LAST NEEDS_NO_SIZE TRUE
J 0
(-2525 4450);
DISPLAY 0.723404 (-2525 4450);
PAINT GREEN (-2525 4450);
DISPLAY INVISIBLE (-2525 4450);
FORCEPROP 1 LAST PATH I142
J 0
(-2525 4450);
DISPLAY 0.723404 (-2525 4450);
PAINT GREEN (-2525 4450);
DISPLAY INVISIBLE (-2525 4450);
FORCEPROP 1 LAST PART_NUMBER AJ051610U03
J 0
(-2875 6000);
DISPLAY 0.723404 (-2875 6000);
PAINT GREEN (-2875 6000);
DISPLAY INVISIBLE (-2875 6000);
FORCEADD Q_CAP_DIFFBUS..2
R 2
(-2350 575);
FORCEPROP 1 LAST LOCATION C6644
J 2
(-2075 575);
DISPLAY 0.723404 (-2075 575);
PAINT GREEN (-2075 575);
FORCEPROP 2 LAST $SEC 1
J 2
(-2175 650);
DISPLAY 0.680851 (-2175 650);
PAINT MONO (-2175 650);
DISPLAY INVISIBLE (-2175 650);
FORCEPROP 2 LAST CDS_SEC 1
J 2
(-2175 650);
DISPLAY 0.680851 (-2175 650);
DISPLAY INVISIBLE (-2175 650);
FORCEPROP 2 LASTPIN (-2275 575) $PN 1
J 0
(-2265 585);
DISPLAY 0.808511 (-2265 585);
FORCEPROP 2 LASTPIN (-2425 575) $PN 2
J 2
(-2435 585);
DISPLAY 0.808511 (-2435 585);
FORCEPROP 2 LAST VALUE DIFF BUS_0.22UF
J 2
(-2500 575);
DISPLAY 0.553191 (-2500 575);
FORCEPROP 2 LAST TOLERANCE 20%
J 2
(-2425 625);
DISPLAY 0.553191 (-2425 625);
DISPLAY INVISIBLE (-2425 625);
FORCEPROP 2 LAST PACK_TYPE C0201
J 2
(-2525 625);
DISPLAY 0.553191 (-2525 625);
DISPLAY INVISIBLE (-2525 625);
FORCEPROP 1 LAST MATERIAL X6S
J 2
(-2341 654);
DISPLAY 0.574468 (-2341 654);
PAINT GREEN (-2341 654);
DISPLAY INVISIBLE (-2341 654);
FORCEPROP 2 LAST VOLTAGE 6.3V
J 2
(-2700 625);
DISPLAY 0.553191 (-2700 625);
DISPLAY INVISIBLE (-2700 625);
FORCEPROP 1 LAST PIN_NAMES_ROTATE TRUE
J 2
(-2350 575);
DISPLAY 0.489362 (-2350 575);
PAINT GREEN (-2350 575);
DISPLAY INVISIBLE (-2350 575);
FORCEPROP 2 LAST CDS_LIB pure_quanta
J 2
(-2350 575);
DISPLAY INVISIBLE (-2350 575);
FORCEPROP 1 LAST CDS_LMAN_SYM_OUTLINE -25,50,25,-50
J 2
(-2350 575);
DISPLAY 0.468085 (-2350 575);
PAINT GREEN (-2350 575);
DISPLAY INVISIBLE (-2350 575);
FORCEPROP 1 LAST PATH I15
J 2
(-2350 575);
DISPLAY 0.723404 (-2350 575);
DISPLAY INVISIBLE (-2350 575);
FORCEPROP 1 LAST PART_NUMBER SP_CH4221MEE01
J 2
(-2466 663);
DISPLAY 0.574468 (-2466 663);
PAINT GREEN (-2466 663);
DISPLAY INVISIBLE (-2466 663);
FORCEPROP 1 LAST LOCATION C6644
J 0
(-2100 650);
DISPLAY 1.021277 (-2100 650);
DISPLAY INVISIBLE (-2100 650);
FORCEADD Q_CAP_DIFFBUS..2
R 2
(-2350 625);
FORCEPROP 1 LAST LOCATION C6643
J 2
(-2075 625);
DISPLAY 0.723404 (-2075 625);
PAINT GREEN (-2075 625);
FORCEPROP 2 LAST $SEC 1
J 2
(-2175 700);
DISPLAY 0.680851 (-2175 700);
PAINT MONO (-2175 700);
DISPLAY INVISIBLE (-2175 700);
FORCEPROP 2 LAST CDS_SEC 1
J 2
(-2175 700);
DISPLAY 0.680851 (-2175 700);
DISPLAY INVISIBLE (-2175 700);
FORCEPROP 2 LASTPIN (-2275 625) $PN 1
J 0
(-2265 635);
DISPLAY 0.808511 (-2265 635);
FORCEPROP 2 LASTPIN (-2425 625) $PN 2
J 2
(-2435 635);
DISPLAY 0.808511 (-2435 635);
FORCEPROP 2 LAST VALUE DIFF BUS_0.22UF
J 2
(-2500 625);
DISPLAY 0.553191 (-2500 625);
FORCEPROP 2 LAST TOLERANCE 20%
J 2
(-2425 675);
DISPLAY 0.553191 (-2425 675);
DISPLAY INVISIBLE (-2425 675);
FORCEPROP 2 LAST PACK_TYPE C0201
J 2
(-2525 675);
DISPLAY 0.553191 (-2525 675);
DISPLAY INVISIBLE (-2525 675);
FORCEPROP 1 LAST MATERIAL X6S
J 2
(-2341 704);
DISPLAY 0.574468 (-2341 704);
PAINT GREEN (-2341 704);
DISPLAY INVISIBLE (-2341 704);
FORCEPROP 2 LAST VOLTAGE 6.3V
J 2
(-2700 675);
DISPLAY 0.553191 (-2700 675);
DISPLAY INVISIBLE (-2700 675);
FORCEPROP 1 LAST PIN_NAMES_ROTATE TRUE
J 2
(-2350 625);
DISPLAY 0.489362 (-2350 625);
PAINT GREEN (-2350 625);
DISPLAY INVISIBLE (-2350 625);
FORCEPROP 2 LAST CDS_LIB pure_quanta
J 2
(-2350 625);
DISPLAY INVISIBLE (-2350 625);
FORCEPROP 1 LAST CDS_LMAN_SYM_OUTLINE -25,50,25,-50
J 2
(-2350 625);
DISPLAY 0.468085 (-2350 625);
PAINT GREEN (-2350 625);
DISPLAY INVISIBLE (-2350 625);
FORCEPROP 1 LAST PATH I16
J 2
(-2350 625);
DISPLAY 0.723404 (-2350 625);
DISPLAY INVISIBLE (-2350 625);
FORCEPROP 1 LAST PART_NUMBER SP_CH4221MEE01
J 2
(-2466 713);
DISPLAY 0.574468 (-2466 713);
PAINT GREEN (-2466 713);
DISPLAY INVISIBLE (-2466 713);
FORCEPROP 1 LAST LOCATION C6643
J 0
(-2100 700);
DISPLAY 1.021277 (-2100 700);
DISPLAY INVISIBLE (-2100 700);
FORCEADD TAP..1
(-1600 575);
FORCEPROP 3 LASTPIN (-1650 575) SIG_NAME P5E_CPU1_P0_TX_BUF_C_DN<7>
J 0
(-1640 585);
DISPLAY 0.659574 (-1640 585);
PAINT MONO (-1640 585);
DISPLAY INVISIBLE (-1640 585);
FORCEPROP 1 LASTPIN (-1650 575) BN 7
J 0
(-1662 583);
DISPLAY 0.680851 (-1662 583);
PAINT GREEN (-1662 583);
FORCEPROP 2 LAST CDS_LIB standard
J 0
(-1600 575);
DISPLAY INVISIBLE (-1600 575);
FORCEPROP 1 LAST BODY_TYPE PLUMBING
J 0
(-1600 625);
DISPLAY 0.872340 (-1600 625);
PAINT GREEN (-1600 625);
DISPLAY INVISIBLE (-1600 625);
FORCEPROP 1 LAST HDL_TAP TRUE
J 0
(-1275 450);
DISPLAY 0.872340 (-1275 450);
DISPLAY INVISIBLE (-1275 450);
FORCEPROP 1 LAST PATH I17
J 0
(-1602 575);
DISPLAY 0.872340 (-1602 575);
PAINT GREEN (-1602 575);
DISPLAY INVISIBLE (-1602 575);
FORCEADD Q_CAP_DIFFBUS..2
R 2
(-2350 825);
FORCEPROP 1 LAST LOCATION C6641
J 2
(-2075 825);
DISPLAY 0.723404 (-2075 825);
PAINT GREEN (-2075 825);
FORCEPROP 2 LAST $SEC 1
J 2
(-2175 900);
DISPLAY 0.680851 (-2175 900);
PAINT MONO (-2175 900);
DISPLAY INVISIBLE (-2175 900);
FORCEPROP 2 LAST CDS_SEC 1
J 2
(-2175 900);
DISPLAY 0.680851 (-2175 900);
DISPLAY INVISIBLE (-2175 900);
FORCEPROP 2 LASTPIN (-2275 825) $PN 1
J 0
(-2265 835);
DISPLAY 0.808511 (-2265 835);
FORCEPROP 2 LASTPIN (-2425 825) $PN 2
J 2
(-2435 835);
DISPLAY 0.808511 (-2435 835);
FORCEPROP 2 LAST VALUE DIFF BUS_0.22UF
J 2
(-2500 825);
DISPLAY 0.553191 (-2500 825);
FORCEPROP 2 LAST TOLERANCE 20%
J 2
(-2425 875);
DISPLAY 0.553191 (-2425 875);
DISPLAY INVISIBLE (-2425 875);
FORCEPROP 2 LAST PACK_TYPE C0201
J 2
(-2525 875);
DISPLAY 0.553191 (-2525 875);
DISPLAY INVISIBLE (-2525 875);
FORCEPROP 1 LAST MATERIAL X6S
J 2
(-2341 904);
DISPLAY 0.574468 (-2341 904);
PAINT GREEN (-2341 904);
DISPLAY INVISIBLE (-2341 904);
FORCEPROP 2 LAST VOLTAGE 6.3V
J 2
(-2700 875);
DISPLAY 0.553191 (-2700 875);
DISPLAY INVISIBLE (-2700 875);
FORCEPROP 1 LAST PIN_NAMES_ROTATE TRUE
J 2
(-2350 825);
DISPLAY 0.489362 (-2350 825);
PAINT GREEN (-2350 825);
DISPLAY INVISIBLE (-2350 825);
FORCEPROP 1 LAST CDS_LMAN_SYM_OUTLINE -25,50,25,-50
J 2
(-2350 825);
DISPLAY 0.468085 (-2350 825);
PAINT GREEN (-2350 825);
DISPLAY INVISIBLE (-2350 825);
FORCEPROP 2 LAST CDS_LIB pure_quanta
J 2
(-2350 825);
DISPLAY INVISIBLE (-2350 825);
FORCEPROP 1 LAST PATH I18
J 2
(-2350 825);
DISPLAY 0.723404 (-2350 825);
DISPLAY INVISIBLE (-2350 825);
FORCEPROP 1 LAST PART_NUMBER SP_CH4221MEE01
J 2
(-2466 913);
DISPLAY 0.574468 (-2466 913);
PAINT GREEN (-2466 913);
DISPLAY INVISIBLE (-2466 913);
FORCEPROP 1 LAST LOCATION C6641
J 0
(-2100 900);
DISPLAY 1.021277 (-2100 900);
DISPLAY INVISIBLE (-2100 900);
FORCEADD Q_CAP_DIFFBUS..2
R 2
(-2350 775);
FORCEPROP 1 LAST LOCATION C6642
J 2
(-2075 775);
DISPLAY 0.723404 (-2075 775);
PAINT GREEN (-2075 775);
FORCEPROP 2 LAST $SEC 1
J 2
(-2175 850);
DISPLAY 0.680851 (-2175 850);
PAINT MONO (-2175 850);
DISPLAY INVISIBLE (-2175 850);
FORCEPROP 2 LAST CDS_SEC 1
J 2
(-2175 850);
DISPLAY 0.680851 (-2175 850);
DISPLAY INVISIBLE (-2175 850);
FORCEPROP 2 LASTPIN (-2275 775) $PN 1
J 0
(-2265 785);
DISPLAY 0.808511 (-2265 785);
FORCEPROP 2 LASTPIN (-2425 775) $PN 2
J 2
(-2435 785);
DISPLAY 0.808511 (-2435 785);
FORCEPROP 2 LAST VALUE DIFF BUS_0.22UF
J 2
(-2500 775);
DISPLAY 0.553191 (-2500 775);
FORCEPROP 2 LAST TOLERANCE 20%
J 2
(-2425 825);
DISPLAY 0.553191 (-2425 825);
DISPLAY INVISIBLE (-2425 825);
FORCEPROP 2 LAST PACK_TYPE C0201
J 2
(-2525 825);
DISPLAY 0.553191 (-2525 825);
DISPLAY INVISIBLE (-2525 825);
FORCEPROP 1 LAST MATERIAL X6S
J 2
(-2341 854);
DISPLAY 0.574468 (-2341 854);
PAINT GREEN (-2341 854);
DISPLAY INVISIBLE (-2341 854);
FORCEPROP 2 LAST VOLTAGE 6.3V
J 2
(-2700 825);
DISPLAY 0.553191 (-2700 825);
DISPLAY INVISIBLE (-2700 825);
FORCEPROP 1 LAST PIN_NAMES_ROTATE TRUE
J 2
(-2350 775);
DISPLAY 0.489362 (-2350 775);
PAINT GREEN (-2350 775);
DISPLAY INVISIBLE (-2350 775);
FORCEPROP 2 LAST CDS_LIB pure_quanta
J 2
(-2350 775);
DISPLAY INVISIBLE (-2350 775);
FORCEPROP 1 LAST CDS_LMAN_SYM_OUTLINE -25,50,25,-50
J 2
(-2350 775);
DISPLAY 0.468085 (-2350 775);
PAINT GREEN (-2350 775);
DISPLAY INVISIBLE (-2350 775);
FORCEPROP 1 LAST PATH I19
J 2
(-2350 775);
DISPLAY 0.723404 (-2350 775);
DISPLAY INVISIBLE (-2350 775);
FORCEPROP 1 LAST PART_NUMBER SP_CH4221MEE01
J 2
(-2466 863);
DISPLAY 0.574468 (-2466 863);
PAINT GREEN (-2466 863);
DISPLAY INVISIBLE (-2466 863);
FORCEPROP 1 LAST LOCATION C6642
J 0
(-2100 850);
DISPLAY 1.021277 (-2100 850);
DISPLAY INVISIBLE (-2100 850);
FORCEADD OFFPAGE..1
(-4275 2050);
FORCEPROP 2 LAST $XR0 320 
J 0
(-4527 2050);
DISPLAY 0.638298 (-4527 2050);
PAINT MONO (-4527 2050);
FORCEPROP 2 LAST CDS_LIB standard
J 0
(-4275 2050);
DISPLAY INVISIBLE (-4275 2050);
FORCEPROP 1 LAST OFFPAGE TRUE
J 0
(-3950 1925);
DISPLAY 0.872340 (-3950 1925);
DISPLAY INVISIBLE (-3950 1925);
FORCEPROP 1 LAST COMMENT_BODY TRUE
J 0
(-4150 1950);
DISPLAY 0.872340 (-4150 1950);
PAINT GREEN (-4150 1950);
DISPLAY INVISIBLE (-4150 1950);
FORCEPROP 2 LAST PATH I2
J 0
(-4525 2100);
DISPLAY 0.680851 (-4525 2100);
DISPLAY INVISIBLE (-4525 2100);
FORCEADD Q_CAP_DIFFBUS..2
R 2
(-2350 1025);
FORCEPROP 1 LAST LOCATION C6639
J 2
(-2075 1025);
DISPLAY 0.723404 (-2075 1025);
PAINT GREEN (-2075 1025);
FORCEPROP 2 LAST $SEC 1
J 2
(-2175 1100);
DISPLAY 0.680851 (-2175 1100);
PAINT MONO (-2175 1100);
DISPLAY INVISIBLE (-2175 1100);
FORCEPROP 2 LAST CDS_SEC 1
J 2
(-2175 1100);
DISPLAY 0.680851 (-2175 1100);
DISPLAY INVISIBLE (-2175 1100);
FORCEPROP 2 LASTPIN (-2275 1025) $PN 1
J 0
(-2265 1035);
DISPLAY 0.808511 (-2265 1035);
FORCEPROP 2 LASTPIN (-2425 1025) $PN 2
J 2
(-2435 1035);
DISPLAY 0.808511 (-2435 1035);
FORCEPROP 2 LAST VALUE DIFF BUS_0.22UF
J 2
(-2500 1025);
DISPLAY 0.553191 (-2500 1025);
FORCEPROP 2 LAST TOLERANCE 20%
J 2
(-2425 1075);
DISPLAY 0.553191 (-2425 1075);
DISPLAY INVISIBLE (-2425 1075);
FORCEPROP 2 LAST PACK_TYPE C0201
J 2
(-2525 1075);
DISPLAY 0.553191 (-2525 1075);
DISPLAY INVISIBLE (-2525 1075);
FORCEPROP 1 LAST MATERIAL X6S
J 2
(-2341 1104);
DISPLAY 0.574468 (-2341 1104);
PAINT GREEN (-2341 1104);
DISPLAY INVISIBLE (-2341 1104);
FORCEPROP 2 LAST VOLTAGE 6.3V
J 2
(-2700 1075);
DISPLAY 0.553191 (-2700 1075);
DISPLAY INVISIBLE (-2700 1075);
FORCEPROP 1 LAST PIN_NAMES_ROTATE TRUE
J 2
(-2350 1025);
DISPLAY 0.489362 (-2350 1025);
PAINT GREEN (-2350 1025);
DISPLAY INVISIBLE (-2350 1025);
FORCEPROP 2 LAST CDS_LIB pure_quanta
J 2
(-2350 1025);
DISPLAY INVISIBLE (-2350 1025);
FORCEPROP 1 LAST CDS_LMAN_SYM_OUTLINE -25,50,25,-50
J 2
(-2350 1025);
DISPLAY 0.468085 (-2350 1025);
PAINT GREEN (-2350 1025);
DISPLAY INVISIBLE (-2350 1025);
FORCEPROP 1 LAST PATH I20
J 2
(-2350 1025);
DISPLAY 0.723404 (-2350 1025);
DISPLAY INVISIBLE (-2350 1025);
FORCEPROP 1 LAST PART_NUMBER SP_CH4221MEE01
J 2
(-2466 1113);
DISPLAY 0.574468 (-2466 1113);
PAINT GREEN (-2466 1113);
DISPLAY INVISIBLE (-2466 1113);
FORCEPROP 1 LAST LOCATION C6639
J 0
(-2100 1100);
DISPLAY 1.021277 (-2100 1100);
DISPLAY INVISIBLE (-2100 1100);
FORCEADD Q_CAP_DIFFBUS..2
R 2
(-2350 975);
FORCEPROP 1 LAST LOCATION C6640
J 2
(-2075 975);
DISPLAY 0.723404 (-2075 975);
PAINT GREEN (-2075 975);
FORCEPROP 2 LAST $SEC 1
J 2
(-2175 1050);
DISPLAY 0.680851 (-2175 1050);
PAINT MONO (-2175 1050);
DISPLAY INVISIBLE (-2175 1050);
FORCEPROP 2 LAST CDS_SEC 1
J 2
(-2175 1050);
DISPLAY 0.680851 (-2175 1050);
DISPLAY INVISIBLE (-2175 1050);
FORCEPROP 2 LASTPIN (-2275 975) $PN 1
J 0
(-2265 985);
DISPLAY 0.808511 (-2265 985);
FORCEPROP 2 LASTPIN (-2425 975) $PN 2
J 2
(-2435 985);
DISPLAY 0.808511 (-2435 985);
FORCEPROP 2 LAST VALUE DIFF BUS_0.22UF
J 2
(-2500 975);
DISPLAY 0.553191 (-2500 975);
FORCEPROP 2 LAST TOLERANCE 20%
J 2
(-2425 1025);
DISPLAY 0.553191 (-2425 1025);
DISPLAY INVISIBLE (-2425 1025);
FORCEPROP 2 LAST PACK_TYPE C0201
J 2
(-2525 1025);
DISPLAY 0.553191 (-2525 1025);
DISPLAY INVISIBLE (-2525 1025);
FORCEPROP 1 LAST MATERIAL X6S
J 2
(-2341 1054);
DISPLAY 0.574468 (-2341 1054);
PAINT GREEN (-2341 1054);
DISPLAY INVISIBLE (-2341 1054);
FORCEPROP 2 LAST VOLTAGE 6.3V
J 2
(-2700 1025);
DISPLAY 0.553191 (-2700 1025);
DISPLAY INVISIBLE (-2700 1025);
FORCEPROP 1 LAST PIN_NAMES_ROTATE TRUE
J 2
(-2350 975);
DISPLAY 0.489362 (-2350 975);
PAINT GREEN (-2350 975);
DISPLAY INVISIBLE (-2350 975);
FORCEPROP 2 LAST CDS_LIB pure_quanta
J 2
(-2350 975);
DISPLAY INVISIBLE (-2350 975);
FORCEPROP 1 LAST CDS_LMAN_SYM_OUTLINE -25,50,25,-50
J 2
(-2350 975);
DISPLAY 0.468085 (-2350 975);
PAINT GREEN (-2350 975);
DISPLAY INVISIBLE (-2350 975);
FORCEPROP 1 LAST PATH I21
J 2
(-2350 975);
DISPLAY 0.723404 (-2350 975);
DISPLAY INVISIBLE (-2350 975);
FORCEPROP 1 LAST PART_NUMBER SP_CH4221MEE01
J 2
(-2466 1063);
DISPLAY 0.574468 (-2466 1063);
PAINT GREEN (-2466 1063);
DISPLAY INVISIBLE (-2466 1063);
FORCEPROP 1 LAST LOCATION C6640
J 0
(-2100 1050);
DISPLAY 1.021277 (-2100 1050);
DISPLAY INVISIBLE (-2100 1050);
FORCEADD Q_CAP_DIFFBUS..2
R 2
(-2350 1225);
FORCEPROP 1 LAST LOCATION C6637
J 2
(-2075 1225);
DISPLAY 0.723404 (-2075 1225);
PAINT GREEN (-2075 1225);
FORCEPROP 2 LAST $SEC 1
J 2
(-2175 1300);
DISPLAY 0.680851 (-2175 1300);
PAINT MONO (-2175 1300);
DISPLAY INVISIBLE (-2175 1300);
FORCEPROP 2 LAST CDS_SEC 1
J 2
(-2175 1300);
DISPLAY 0.680851 (-2175 1300);
DISPLAY INVISIBLE (-2175 1300);
FORCEPROP 2 LASTPIN (-2275 1225) $PN 1
J 0
(-2265 1235);
DISPLAY 0.808511 (-2265 1235);
FORCEPROP 2 LASTPIN (-2425 1225) $PN 2
J 2
(-2435 1235);
DISPLAY 0.808511 (-2435 1235);
FORCEPROP 2 LAST VALUE DIFF BUS_0.22UF
J 2
(-2500 1225);
DISPLAY 0.553191 (-2500 1225);
FORCEPROP 2 LAST TOLERANCE 20%
J 2
(-2425 1275);
DISPLAY 0.553191 (-2425 1275);
DISPLAY INVISIBLE (-2425 1275);
FORCEPROP 2 LAST PACK_TYPE C0201
J 2
(-2525 1275);
DISPLAY 0.553191 (-2525 1275);
DISPLAY INVISIBLE (-2525 1275);
FORCEPROP 1 LAST MATERIAL X6S
J 2
(-2341 1304);
DISPLAY 0.574468 (-2341 1304);
PAINT GREEN (-2341 1304);
DISPLAY INVISIBLE (-2341 1304);
FORCEPROP 2 LAST VOLTAGE 6.3V
J 2
(-2700 1275);
DISPLAY 0.553191 (-2700 1275);
DISPLAY INVISIBLE (-2700 1275);
FORCEPROP 1 LAST PIN_NAMES_ROTATE TRUE
J 2
(-2350 1225);
DISPLAY 0.489362 (-2350 1225);
PAINT GREEN (-2350 1225);
DISPLAY INVISIBLE (-2350 1225);
FORCEPROP 1 LAST CDS_LMAN_SYM_OUTLINE -25,50,25,-50
J 2
(-2350 1225);
DISPLAY 0.468085 (-2350 1225);
PAINT GREEN (-2350 1225);
DISPLAY INVISIBLE (-2350 1225);
FORCEPROP 2 LAST CDS_LIB pure_quanta
J 2
(-2350 1225);
DISPLAY INVISIBLE (-2350 1225);
FORCEPROP 1 LAST PATH I22
J 2
(-2350 1225);
DISPLAY 0.723404 (-2350 1225);
DISPLAY INVISIBLE (-2350 1225);
FORCEPROP 1 LAST PART_NUMBER SP_CH4221MEE01
J 2
(-2466 1313);
DISPLAY 0.574468 (-2466 1313);
PAINT GREEN (-2466 1313);
DISPLAY INVISIBLE (-2466 1313);
FORCEPROP 1 LAST LOCATION C6637
J 0
(-2100 1300);
DISPLAY 1.021277 (-2100 1300);
DISPLAY INVISIBLE (-2100 1300);
FORCEADD Q_CAP_DIFFBUS..2
R 2
(-2350 1175);
FORCEPROP 1 LAST LOCATION C6638
J 2
(-2075 1175);
DISPLAY 0.723404 (-2075 1175);
PAINT GREEN (-2075 1175);
FORCEPROP 2 LAST $SEC 1
J 2
(-2175 1250);
DISPLAY 0.680851 (-2175 1250);
PAINT MONO (-2175 1250);
DISPLAY INVISIBLE (-2175 1250);
FORCEPROP 2 LAST CDS_SEC 1
J 2
(-2175 1250);
DISPLAY 0.680851 (-2175 1250);
DISPLAY INVISIBLE (-2175 1250);
FORCEPROP 2 LASTPIN (-2275 1175) $PN 1
J 0
(-2265 1185);
DISPLAY 0.808511 (-2265 1185);
FORCEPROP 2 LASTPIN (-2425 1175) $PN 2
J 2
(-2435 1185);
DISPLAY 0.808511 (-2435 1185);
FORCEPROP 2 LAST VALUE DIFF BUS_0.22UF
J 2
(-2500 1175);
DISPLAY 0.553191 (-2500 1175);
FORCEPROP 2 LAST TOLERANCE 20%
J 2
(-2425 1225);
DISPLAY 0.553191 (-2425 1225);
DISPLAY INVISIBLE (-2425 1225);
FORCEPROP 2 LAST PACK_TYPE C0201
J 2
(-2525 1225);
DISPLAY 0.553191 (-2525 1225);
DISPLAY INVISIBLE (-2525 1225);
FORCEPROP 1 LAST MATERIAL X6S
J 2
(-2341 1254);
DISPLAY 0.574468 (-2341 1254);
PAINT GREEN (-2341 1254);
DISPLAY INVISIBLE (-2341 1254);
FORCEPROP 2 LAST VOLTAGE 6.3V
J 2
(-2700 1225);
DISPLAY 0.553191 (-2700 1225);
DISPLAY INVISIBLE (-2700 1225);
FORCEPROP 1 LAST PIN_NAMES_ROTATE TRUE
J 2
(-2350 1175);
DISPLAY 0.489362 (-2350 1175);
PAINT GREEN (-2350 1175);
DISPLAY INVISIBLE (-2350 1175);
FORCEPROP 1 LAST CDS_LMAN_SYM_OUTLINE -25,50,25,-50
J 2
(-2350 1175);
DISPLAY 0.468085 (-2350 1175);
PAINT GREEN (-2350 1175);
DISPLAY INVISIBLE (-2350 1175);
FORCEPROP 2 LAST CDS_LIB pure_quanta
J 2
(-2350 1175);
DISPLAY INVISIBLE (-2350 1175);
FORCEPROP 1 LAST PATH I23
J 2
(-2350 1175);
DISPLAY 0.723404 (-2350 1175);
DISPLAY INVISIBLE (-2350 1175);
FORCEPROP 1 LAST PART_NUMBER SP_CH4221MEE01
J 2
(-2466 1263);
DISPLAY 0.574468 (-2466 1263);
PAINT GREEN (-2466 1263);
DISPLAY INVISIBLE (-2466 1263);
FORCEPROP 1 LAST LOCATION C6638
J 0
(-2100 1250);
DISPLAY 1.021277 (-2100 1250);
DISPLAY INVISIBLE (-2100 1250);
FORCEADD Q_CAP_DIFFBUS..2
R 2
(-2350 1375);
FORCEPROP 1 LAST LOCATION C6636
J 2
(-2075 1375);
DISPLAY 0.723404 (-2075 1375);
PAINT GREEN (-2075 1375);
FORCEPROP 2 LAST $SEC 1
J 2
(-2175 1450);
DISPLAY 0.680851 (-2175 1450);
PAINT MONO (-2175 1450);
DISPLAY INVISIBLE (-2175 1450);
FORCEPROP 2 LAST CDS_SEC 1
J 2
(-2175 1450);
DISPLAY 0.680851 (-2175 1450);
DISPLAY INVISIBLE (-2175 1450);
FORCEPROP 2 LASTPIN (-2275 1375) $PN 1
J 0
(-2265 1385);
DISPLAY 0.808511 (-2265 1385);
FORCEPROP 2 LASTPIN (-2425 1375) $PN 2
J 2
(-2435 1385);
DISPLAY 0.808511 (-2435 1385);
FORCEPROP 2 LAST VALUE DIFF BUS_0.22UF
J 2
(-2500 1375);
DISPLAY 0.553191 (-2500 1375);
FORCEPROP 2 LAST TOLERANCE 20%
J 2
(-2425 1425);
DISPLAY 0.553191 (-2425 1425);
DISPLAY INVISIBLE (-2425 1425);
FORCEPROP 2 LAST PACK_TYPE C0201
J 2
(-2525 1425);
DISPLAY 0.553191 (-2525 1425);
DISPLAY INVISIBLE (-2525 1425);
FORCEPROP 1 LAST MATERIAL X6S
J 2
(-2341 1454);
DISPLAY 0.574468 (-2341 1454);
PAINT GREEN (-2341 1454);
DISPLAY INVISIBLE (-2341 1454);
FORCEPROP 2 LAST VOLTAGE 6.3V
J 2
(-2700 1425);
DISPLAY 0.553191 (-2700 1425);
DISPLAY INVISIBLE (-2700 1425);
FORCEPROP 1 LAST PIN_NAMES_ROTATE TRUE
J 2
(-2350 1375);
DISPLAY 0.489362 (-2350 1375);
PAINT GREEN (-2350 1375);
DISPLAY INVISIBLE (-2350 1375);
FORCEPROP 2 LAST CDS_LIB pure_quanta
J 2
(-2350 1375);
DISPLAY INVISIBLE (-2350 1375);
FORCEPROP 1 LAST CDS_LMAN_SYM_OUTLINE -25,50,25,-50
J 2
(-2350 1375);
DISPLAY 0.468085 (-2350 1375);
PAINT GREEN (-2350 1375);
DISPLAY INVISIBLE (-2350 1375);
FORCEPROP 1 LAST PATH I24
J 2
(-2350 1375);
DISPLAY 0.723404 (-2350 1375);
DISPLAY INVISIBLE (-2350 1375);
FORCEPROP 1 LAST PART_NUMBER SP_CH4221MEE01
J 2
(-2466 1463);
DISPLAY 0.574468 (-2466 1463);
PAINT GREEN (-2466 1463);
DISPLAY INVISIBLE (-2466 1463);
FORCEPROP 1 LAST LOCATION C6636
J 0
(-2100 1450);
DISPLAY 1.021277 (-2100 1450);
DISPLAY INVISIBLE (-2100 1450);
FORCEADD Q_CAP_DIFFBUS..2
R 2
(-2350 1425);
FORCEPROP 1 LAST LOCATION C6635
J 2
(-2075 1425);
DISPLAY 0.723404 (-2075 1425);
PAINT GREEN (-2075 1425);
FORCEPROP 2 LAST $SEC 1
J 2
(-2175 1500);
DISPLAY 0.680851 (-2175 1500);
PAINT MONO (-2175 1500);
DISPLAY INVISIBLE (-2175 1500);
FORCEPROP 2 LAST CDS_SEC 1
J 2
(-2175 1500);
DISPLAY 0.680851 (-2175 1500);
DISPLAY INVISIBLE (-2175 1500);
FORCEPROP 2 LASTPIN (-2275 1425) $PN 1
J 0
(-2265 1435);
DISPLAY 0.808511 (-2265 1435);
FORCEPROP 2 LASTPIN (-2425 1425) $PN 2
J 2
(-2435 1435);
DISPLAY 0.808511 (-2435 1435);
FORCEPROP 2 LAST VALUE DIFF BUS_0.22UF
J 2
(-2500 1425);
DISPLAY 0.553191 (-2500 1425);
FORCEPROP 2 LAST TOLERANCE 20%
J 2
(-2425 1475);
DISPLAY 0.553191 (-2425 1475);
DISPLAY INVISIBLE (-2425 1475);
FORCEPROP 2 LAST PACK_TYPE C0201
J 2
(-2525 1475);
DISPLAY 0.553191 (-2525 1475);
DISPLAY INVISIBLE (-2525 1475);
FORCEPROP 1 LAST MATERIAL X6S
J 2
(-2341 1504);
DISPLAY 0.574468 (-2341 1504);
PAINT GREEN (-2341 1504);
DISPLAY INVISIBLE (-2341 1504);
FORCEPROP 2 LAST VOLTAGE 6.3V
J 2
(-2700 1475);
DISPLAY 0.553191 (-2700 1475);
DISPLAY INVISIBLE (-2700 1475);
FORCEPROP 1 LAST PIN_NAMES_ROTATE TRUE
J 2
(-2350 1425);
DISPLAY 0.489362 (-2350 1425);
PAINT GREEN (-2350 1425);
DISPLAY INVISIBLE (-2350 1425);
FORCEPROP 2 LAST CDS_LIB pure_quanta
J 2
(-2350 1425);
DISPLAY INVISIBLE (-2350 1425);
FORCEPROP 1 LAST CDS_LMAN_SYM_OUTLINE -25,50,25,-50
J 2
(-2350 1425);
DISPLAY 0.468085 (-2350 1425);
PAINT GREEN (-2350 1425);
DISPLAY INVISIBLE (-2350 1425);
FORCEPROP 1 LAST PATH I25
J 2
(-2350 1425);
DISPLAY 0.723404 (-2350 1425);
DISPLAY INVISIBLE (-2350 1425);
FORCEPROP 1 LAST PART_NUMBER SP_CH4221MEE01
J 2
(-2466 1513);
DISPLAY 0.574468 (-2466 1513);
PAINT GREEN (-2466 1513);
DISPLAY INVISIBLE (-2466 1513);
FORCEPROP 1 LAST LOCATION C6635
J 0
(-2100 1500);
DISPLAY 1.021277 (-2100 1500);
DISPLAY INVISIBLE (-2100 1500);
FORCEADD Q_CAP_DIFFBUS..2
R 2
(-2350 1575);
FORCEPROP 1 LAST LOCATION C6634
J 2
(-2075 1575);
DISPLAY 0.723404 (-2075 1575);
PAINT GREEN (-2075 1575);
FORCEPROP 2 LAST $SEC 1
J 2
(-2175 1650);
DISPLAY 0.680851 (-2175 1650);
PAINT MONO (-2175 1650);
DISPLAY INVISIBLE (-2175 1650);
FORCEPROP 2 LAST CDS_SEC 1
J 2
(-2175 1650);
DISPLAY 0.680851 (-2175 1650);
DISPLAY INVISIBLE (-2175 1650);
FORCEPROP 2 LASTPIN (-2275 1575) $PN 1
J 0
(-2265 1585);
DISPLAY 0.808511 (-2265 1585);
FORCEPROP 2 LASTPIN (-2425 1575) $PN 2
J 2
(-2435 1585);
DISPLAY 0.808511 (-2435 1585);
FORCEPROP 2 LAST VALUE DIFF BUS_0.22UF
J 2
(-2500 1575);
DISPLAY 0.553191 (-2500 1575);
FORCEPROP 2 LAST TOLERANCE 20%
J 2
(-2425 1625);
DISPLAY 0.553191 (-2425 1625);
DISPLAY INVISIBLE (-2425 1625);
FORCEPROP 2 LAST PACK_TYPE C0201
J 2
(-2525 1625);
DISPLAY 0.553191 (-2525 1625);
DISPLAY INVISIBLE (-2525 1625);
FORCEPROP 1 LAST MATERIAL X6S
J 2
(-2341 1654);
DISPLAY 0.574468 (-2341 1654);
PAINT GREEN (-2341 1654);
DISPLAY INVISIBLE (-2341 1654);
FORCEPROP 2 LAST VOLTAGE 6.3V
J 2
(-2700 1625);
DISPLAY 0.553191 (-2700 1625);
DISPLAY INVISIBLE (-2700 1625);
FORCEPROP 1 LAST PIN_NAMES_ROTATE TRUE
J 2
(-2350 1575);
DISPLAY 0.489362 (-2350 1575);
PAINT GREEN (-2350 1575);
DISPLAY INVISIBLE (-2350 1575);
FORCEPROP 2 LAST CDS_LIB pure_quanta
J 2
(-2350 1575);
DISPLAY INVISIBLE (-2350 1575);
FORCEPROP 1 LAST CDS_LMAN_SYM_OUTLINE -25,50,25,-50
J 2
(-2350 1575);
DISPLAY 0.468085 (-2350 1575);
PAINT GREEN (-2350 1575);
DISPLAY INVISIBLE (-2350 1575);
FORCEPROP 1 LAST PATH I26
J 2
(-2350 1575);
DISPLAY 0.723404 (-2350 1575);
DISPLAY INVISIBLE (-2350 1575);
FORCEPROP 1 LAST PART_NUMBER SP_CH4221MEE01
J 2
(-2466 1663);
DISPLAY 0.574468 (-2466 1663);
PAINT GREEN (-2466 1663);
DISPLAY INVISIBLE (-2466 1663);
FORCEPROP 1 LAST LOCATION C6634
J 0
(-2100 1650);
DISPLAY 1.021277 (-2100 1650);
DISPLAY INVISIBLE (-2100 1650);
FORCEADD Q_CAP_DIFFBUS..2
R 2
(-2350 1625);
FORCEPROP 1 LAST LOCATION C6633
J 2
(-2075 1625);
DISPLAY 0.723404 (-2075 1625);
PAINT GREEN (-2075 1625);
FORCEPROP 2 LAST $SEC 1
J 2
(-2175 1700);
DISPLAY 0.680851 (-2175 1700);
PAINT MONO (-2175 1700);
DISPLAY INVISIBLE (-2175 1700);
FORCEPROP 2 LAST CDS_SEC 1
J 2
(-2175 1700);
DISPLAY 0.680851 (-2175 1700);
DISPLAY INVISIBLE (-2175 1700);
FORCEPROP 2 LASTPIN (-2275 1625) $PN 1
J 0
(-2265 1635);
DISPLAY 0.808511 (-2265 1635);
FORCEPROP 2 LASTPIN (-2425 1625) $PN 2
J 2
(-2435 1635);
DISPLAY 0.808511 (-2435 1635);
FORCEPROP 2 LAST VALUE DIFF BUS_0.22UF
J 2
(-2500 1625);
DISPLAY 0.553191 (-2500 1625);
FORCEPROP 2 LAST TOLERANCE 20%
J 2
(-2425 1675);
DISPLAY 0.553191 (-2425 1675);
DISPLAY INVISIBLE (-2425 1675);
FORCEPROP 2 LAST PACK_TYPE C0201
J 2
(-2525 1675);
DISPLAY 0.553191 (-2525 1675);
DISPLAY INVISIBLE (-2525 1675);
FORCEPROP 1 LAST MATERIAL X6S
J 2
(-2341 1704);
DISPLAY 0.574468 (-2341 1704);
PAINT GREEN (-2341 1704);
DISPLAY INVISIBLE (-2341 1704);
FORCEPROP 2 LAST VOLTAGE 6.3V
J 2
(-2700 1675);
DISPLAY 0.553191 (-2700 1675);
DISPLAY INVISIBLE (-2700 1675);
FORCEPROP 1 LAST PIN_NAMES_ROTATE TRUE
J 2
(-2350 1625);
DISPLAY 0.489362 (-2350 1625);
PAINT GREEN (-2350 1625);
DISPLAY INVISIBLE (-2350 1625);
FORCEPROP 2 LAST CDS_LIB pure_quanta
J 2
(-2350 1625);
DISPLAY INVISIBLE (-2350 1625);
FORCEPROP 1 LAST CDS_LMAN_SYM_OUTLINE -25,50,25,-50
J 2
(-2350 1625);
DISPLAY 0.468085 (-2350 1625);
PAINT GREEN (-2350 1625);
DISPLAY INVISIBLE (-2350 1625);
FORCEPROP 1 LAST PATH I27
J 2
(-2350 1625);
DISPLAY 0.723404 (-2350 1625);
DISPLAY INVISIBLE (-2350 1625);
FORCEPROP 1 LAST PART_NUMBER SP_CH4221MEE01
J 2
(-2466 1713);
DISPLAY 0.574468 (-2466 1713);
PAINT GREEN (-2466 1713);
DISPLAY INVISIBLE (-2466 1713);
FORCEPROP 1 LAST LOCATION C6633
J 0
(-2100 1700);
DISPLAY 1.021277 (-2100 1700);
DISPLAY INVISIBLE (-2100 1700);
FORCEADD TAP..1
(-1800 625);
FORCEPROP 3 LASTPIN (-1850 625) SIG_NAME P5E_CPU1_P0_TX_BUF_C_DP<7>
J 0
(-1840 635);
DISPLAY 0.659574 (-1840 635);
PAINT MONO (-1840 635);
DISPLAY INVISIBLE (-1840 635);
FORCEPROP 1 LASTPIN (-1850 625) BN 7
J 0
(-1862 633);
DISPLAY 0.680851 (-1862 633);
PAINT GREEN (-1862 633);
FORCEPROP 2 LAST CDS_LIB standard
J 0
(-1800 625);
DISPLAY INVISIBLE (-1800 625);
FORCEPROP 1 LAST BODY_TYPE PLUMBING
J 0
(-1800 675);
DISPLAY 0.872340 (-1800 675);
PAINT GREEN (-1800 675);
DISPLAY INVISIBLE (-1800 675);
FORCEPROP 1 LAST HDL_TAP TRUE
J 0
(-1475 500);
DISPLAY 0.872340 (-1475 500);
DISPLAY INVISIBLE (-1475 500);
FORCEPROP 1 LAST PATH I28
J 0
(-1802 625);
DISPLAY 0.872340 (-1802 625);
PAINT GREEN (-1802 625);
DISPLAY INVISIBLE (-1802 625);
FORCEADD TAP..1
(-1800 1025);
FORCEPROP 3 LASTPIN (-1850 1025) SIG_NAME P5E_CPU1_P0_TX_BUF_C_DP<5>
J 0
(-1840 1035);
DISPLAY 0.659574 (-1840 1035);
PAINT MONO (-1840 1035);
DISPLAY INVISIBLE (-1840 1035);
FORCEPROP 1 LASTPIN (-1850 1025) BN 5
J 0
(-1862 1033);
DISPLAY 0.680851 (-1862 1033);
PAINT GREEN (-1862 1033);
FORCEPROP 2 LAST CDS_LIB standard
J 0
(-1800 1025);
DISPLAY INVISIBLE (-1800 1025);
FORCEPROP 1 LAST BODY_TYPE PLUMBING
J 0
(-1800 1075);
DISPLAY 0.872340 (-1800 1075);
PAINT GREEN (-1800 1075);
DISPLAY INVISIBLE (-1800 1075);
FORCEPROP 1 LAST HDL_TAP TRUE
J 0
(-1475 900);
DISPLAY 0.872340 (-1475 900);
DISPLAY INVISIBLE (-1475 900);
FORCEPROP 1 LAST PATH I29
J 0
(-1802 1025);
DISPLAY 0.872340 (-1802 1025);
PAINT GREEN (-1802 1025);
DISPLAY INVISIBLE (-1802 1025);
FORCEADD TAP..1
R 2
(-3325 575);
FORCEPROP 3 LASTPIN (-3275 575) SIG_NAME P5E_CPU1_P0_TX_BUF_DN<7>
J 0
(-3265 585);
DISPLAY 0.659574 (-3265 585);
PAINT MONO (-3265 585);
DISPLAY INVISIBLE (-3265 585);
FORCEPROP 1 LASTPIN (-3275 575) BN 7
J 2
(-3263 583);
DISPLAY 0.680851 (-3263 583);
PAINT GREEN (-3263 583);
FORCEPROP 2 LAST CDS_LIB standard
J 0
(-3325 575);
DISPLAY INVISIBLE (-3325 575);
FORCEPROP 1 LAST BODY_TYPE PLUMBING
J 2
(-3325 625);
DISPLAY 0.872340 (-3325 625);
PAINT GREEN (-3325 625);
DISPLAY INVISIBLE (-3325 625);
FORCEPROP 1 LAST HDL_TAP TRUE
J 2
(-3650 450);
DISPLAY 0.872340 (-3650 450);
DISPLAY INVISIBLE (-3650 450);
FORCEPROP 1 LAST PATH I3
J 2
(-3323 575);
DISPLAY 0.872340 (-3323 575);
PAINT GREEN (-3323 575);
DISPLAY INVISIBLE (-3323 575);
FORCEADD TAP..1
(-1800 825);
FORCEPROP 3 LASTPIN (-1850 825) SIG_NAME P5E_CPU1_P0_TX_BUF_C_DP<6>
J 0
(-1840 835);
DISPLAY 0.659574 (-1840 835);
PAINT MONO (-1840 835);
DISPLAY INVISIBLE (-1840 835);
FORCEPROP 1 LASTPIN (-1850 825) BN 6
J 0
(-1862 833);
DISPLAY 0.680851 (-1862 833);
PAINT GREEN (-1862 833);
FORCEPROP 2 LAST CDS_LIB standard
J 0
(-1800 825);
DISPLAY INVISIBLE (-1800 825);
FORCEPROP 1 LAST BODY_TYPE PLUMBING
J 0
(-1800 875);
DISPLAY 0.872340 (-1800 875);
PAINT GREEN (-1800 875);
DISPLAY INVISIBLE (-1800 875);
FORCEPROP 1 LAST HDL_TAP TRUE
J 0
(-1475 700);
DISPLAY 0.872340 (-1475 700);
DISPLAY INVISIBLE (-1475 700);
FORCEPROP 1 LAST PATH I30
J 0
(-1802 825);
DISPLAY 0.872340 (-1802 825);
PAINT GREEN (-1802 825);
DISPLAY INVISIBLE (-1802 825);
FORCEADD TAP..1
(-1600 775);
FORCEPROP 3 LASTPIN (-1650 775) SIG_NAME P5E_CPU1_P0_TX_BUF_C_DN<6>
J 0
(-1640 785);
DISPLAY 0.659574 (-1640 785);
PAINT MONO (-1640 785);
DISPLAY INVISIBLE (-1640 785);
FORCEPROP 1 LASTPIN (-1650 775) BN 6
J 0
(-1662 783);
DISPLAY 0.680851 (-1662 783);
PAINT GREEN (-1662 783);
FORCEPROP 2 LAST CDS_LIB standard
J 0
(-1600 775);
DISPLAY INVISIBLE (-1600 775);
FORCEPROP 1 LAST BODY_TYPE PLUMBING
J 0
(-1600 825);
DISPLAY 0.872340 (-1600 825);
PAINT GREEN (-1600 825);
DISPLAY INVISIBLE (-1600 825);
FORCEPROP 1 LAST HDL_TAP TRUE
J 0
(-1275 650);
DISPLAY 0.872340 (-1275 650);
DISPLAY INVISIBLE (-1275 650);
FORCEPROP 1 LAST PATH I31
J 0
(-1602 775);
DISPLAY 0.872340 (-1602 775);
PAINT GREEN (-1602 775);
DISPLAY INVISIBLE (-1602 775);
FORCEADD TAP..1
(-1600 975);
FORCEPROP 3 LASTPIN (-1650 975) SIG_NAME P5E_CPU1_P0_TX_BUF_C_DN<5>
J 0
(-1640 985);
DISPLAY 0.659574 (-1640 985);
PAINT MONO (-1640 985);
DISPLAY INVISIBLE (-1640 985);
FORCEPROP 1 LASTPIN (-1650 975) BN 5
J 0
(-1662 983);
DISPLAY 0.680851 (-1662 983);
PAINT GREEN (-1662 983);
FORCEPROP 2 LAST CDS_LIB standard
J 0
(-1600 975);
DISPLAY INVISIBLE (-1600 975);
FORCEPROP 1 LAST BODY_TYPE PLUMBING
J 0
(-1600 1025);
DISPLAY 0.872340 (-1600 1025);
PAINT GREEN (-1600 1025);
DISPLAY INVISIBLE (-1600 1025);
FORCEPROP 1 LAST HDL_TAP TRUE
J 0
(-1275 850);
DISPLAY 0.872340 (-1275 850);
DISPLAY INVISIBLE (-1275 850);
FORCEPROP 1 LAST PATH I32
J 0
(-1602 975);
DISPLAY 0.872340 (-1602 975);
PAINT GREEN (-1602 975);
DISPLAY INVISIBLE (-1602 975);
FORCEADD TAP..1
(-1800 1425);
FORCEPROP 3 LASTPIN (-1850 1425) SIG_NAME P5E_CPU1_P0_TX_BUF_C_DP<3>
J 0
(-1840 1435);
DISPLAY 0.659574 (-1840 1435);
PAINT MONO (-1840 1435);
DISPLAY INVISIBLE (-1840 1435);
FORCEPROP 1 LASTPIN (-1850 1425) BN 3
J 0
(-1862 1433);
DISPLAY 0.680851 (-1862 1433);
PAINT GREEN (-1862 1433);
FORCEPROP 2 LAST CDS_LIB standard
J 0
(-1800 1425);
DISPLAY INVISIBLE (-1800 1425);
FORCEPROP 1 LAST BODY_TYPE PLUMBING
J 0
(-1800 1475);
DISPLAY 0.872340 (-1800 1475);
PAINT GREEN (-1800 1475);
DISPLAY INVISIBLE (-1800 1475);
FORCEPROP 1 LAST HDL_TAP TRUE
J 0
(-1475 1300);
DISPLAY 0.872340 (-1475 1300);
DISPLAY INVISIBLE (-1475 1300);
FORCEPROP 1 LAST PATH I33
J 0
(-1802 1425);
DISPLAY 0.872340 (-1802 1425);
PAINT GREEN (-1802 1425);
DISPLAY INVISIBLE (-1802 1425);
FORCEADD TAP..1
(-1800 1625);
FORCEPROP 3 LASTPIN (-1850 1625) SIG_NAME P5E_CPU1_P0_TX_BUF_C_DP<2>
J 0
(-1840 1635);
DISPLAY 0.659574 (-1840 1635);
PAINT MONO (-1840 1635);
DISPLAY INVISIBLE (-1840 1635);
FORCEPROP 1 LASTPIN (-1850 1625) BN 2
J 0
(-1862 1633);
DISPLAY 0.680851 (-1862 1633);
PAINT GREEN (-1862 1633);
FORCEPROP 2 LAST CDS_LIB standard
J 0
(-1800 1625);
DISPLAY INVISIBLE (-1800 1625);
FORCEPROP 1 LAST BODY_TYPE PLUMBING
J 0
(-1800 1675);
DISPLAY 0.872340 (-1800 1675);
PAINT GREEN (-1800 1675);
DISPLAY INVISIBLE (-1800 1675);
FORCEPROP 1 LAST HDL_TAP TRUE
J 0
(-1475 1500);
DISPLAY 0.872340 (-1475 1500);
DISPLAY INVISIBLE (-1475 1500);
FORCEPROP 1 LAST PATH I34
J 0
(-1802 1625);
DISPLAY 0.872340 (-1802 1625);
PAINT GREEN (-1802 1625);
DISPLAY INVISIBLE (-1802 1625);
FORCEADD TAP..1
(-1800 1225);
FORCEPROP 3 LASTPIN (-1850 1225) SIG_NAME P5E_CPU1_P0_TX_BUF_C_DP<4>
J 0
(-1840 1235);
DISPLAY 0.659574 (-1840 1235);
PAINT MONO (-1840 1235);
DISPLAY INVISIBLE (-1840 1235);
FORCEPROP 1 LASTPIN (-1850 1225) BN 4
J 0
(-1862 1233);
DISPLAY 0.680851 (-1862 1233);
PAINT GREEN (-1862 1233);
FORCEPROP 2 LAST CDS_LIB standard
J 0
(-1800 1225);
DISPLAY INVISIBLE (-1800 1225);
FORCEPROP 1 LAST BODY_TYPE PLUMBING
J 0
(-1800 1275);
DISPLAY 0.872340 (-1800 1275);
PAINT GREEN (-1800 1275);
DISPLAY INVISIBLE (-1800 1275);
FORCEPROP 1 LAST HDL_TAP TRUE
J 0
(-1475 1100);
DISPLAY 0.872340 (-1475 1100);
DISPLAY INVISIBLE (-1475 1100);
FORCEPROP 1 LAST PATH I35
J 0
(-1802 1225);
DISPLAY 0.872340 (-1802 1225);
PAINT GREEN (-1802 1225);
DISPLAY INVISIBLE (-1802 1225);
FORCEADD TAP..1
(-1600 1375);
FORCEPROP 3 LASTPIN (-1650 1375) SIG_NAME P5E_CPU1_P0_TX_BUF_C_DN<3>
J 0
(-1640 1385);
DISPLAY 0.659574 (-1640 1385);
PAINT MONO (-1640 1385);
DISPLAY INVISIBLE (-1640 1385);
FORCEPROP 1 LASTPIN (-1650 1375) BN 3
J 0
(-1662 1383);
DISPLAY 0.680851 (-1662 1383);
PAINT GREEN (-1662 1383);
FORCEPROP 2 LAST CDS_LIB standard
J 0
(-1600 1375);
DISPLAY INVISIBLE (-1600 1375);
FORCEPROP 1 LAST BODY_TYPE PLUMBING
J 0
(-1600 1425);
DISPLAY 0.872340 (-1600 1425);
PAINT GREEN (-1600 1425);
DISPLAY INVISIBLE (-1600 1425);
FORCEPROP 1 LAST HDL_TAP TRUE
J 0
(-1275 1250);
DISPLAY 0.872340 (-1275 1250);
DISPLAY INVISIBLE (-1275 1250);
FORCEPROP 1 LAST PATH I36
J 0
(-1602 1375);
DISPLAY 0.872340 (-1602 1375);
PAINT GREEN (-1602 1375);
DISPLAY INVISIBLE (-1602 1375);
FORCEADD TAP..1
(-1600 1175);
FORCEPROP 3 LASTPIN (-1650 1175) SIG_NAME P5E_CPU1_P0_TX_BUF_C_DN<4>
J 0
(-1640 1185);
DISPLAY 0.659574 (-1640 1185);
PAINT MONO (-1640 1185);
DISPLAY INVISIBLE (-1640 1185);
FORCEPROP 1 LASTPIN (-1650 1175) BN 4
J 0
(-1662 1183);
DISPLAY 0.680851 (-1662 1183);
PAINT GREEN (-1662 1183);
FORCEPROP 2 LAST CDS_LIB standard
J 0
(-1600 1175);
DISPLAY INVISIBLE (-1600 1175);
FORCEPROP 1 LAST BODY_TYPE PLUMBING
J 0
(-1600 1225);
DISPLAY 0.872340 (-1600 1225);
PAINT GREEN (-1600 1225);
DISPLAY INVISIBLE (-1600 1225);
FORCEPROP 1 LAST HDL_TAP TRUE
J 0
(-1275 1050);
DISPLAY 0.872340 (-1275 1050);
DISPLAY INVISIBLE (-1275 1050);
FORCEPROP 1 LAST PATH I37
J 0
(-1602 1175);
DISPLAY 0.872340 (-1602 1175);
PAINT GREEN (-1602 1175);
DISPLAY INVISIBLE (-1602 1175);
FORCEADD TAP..1
(-1600 1575);
FORCEPROP 3 LASTPIN (-1650 1575) SIG_NAME P5E_CPU1_P0_TX_BUF_C_DN<2>
J 0
(-1640 1585);
DISPLAY 0.659574 (-1640 1585);
PAINT MONO (-1640 1585);
DISPLAY INVISIBLE (-1640 1585);
FORCEPROP 1 LASTPIN (-1650 1575) BN 2
J 0
(-1662 1583);
DISPLAY 0.680851 (-1662 1583);
PAINT GREEN (-1662 1583);
FORCEPROP 2 LAST CDS_LIB standard
J 0
(-1600 1575);
DISPLAY INVISIBLE (-1600 1575);
FORCEPROP 1 LAST BODY_TYPE PLUMBING
J 0
(-1600 1625);
DISPLAY 0.872340 (-1600 1625);
PAINT GREEN (-1600 1625);
DISPLAY INVISIBLE (-1600 1625);
FORCEPROP 1 LAST HDL_TAP TRUE
J 0
(-1275 1450);
DISPLAY 0.872340 (-1275 1450);
DISPLAY INVISIBLE (-1275 1450);
FORCEPROP 1 LAST PATH I38
J 0
(-1602 1575);
DISPLAY 0.872340 (-1602 1575);
PAINT GREEN (-1602 1575);
DISPLAY INVISIBLE (-1602 1575);
FORCEADD TAP..1
R 2
(-3325 1775);
FORCEPROP 3 LASTPIN (-3275 1775) SIG_NAME P5E_CPU1_P0_TX_BUF_DN<1>
J 0
(-3265 1785);
DISPLAY 0.659574 (-3265 1785);
PAINT MONO (-3265 1785);
DISPLAY INVISIBLE (-3265 1785);
FORCEPROP 1 LASTPIN (-3275 1775) BN 1
J 2
(-3263 1783);
DISPLAY 0.680851 (-3263 1783);
PAINT GREEN (-3263 1783);
FORCEPROP 2 LAST CDS_LIB standard
J 0
(-3325 1775);
DISPLAY INVISIBLE (-3325 1775);
FORCEPROP 1 LAST BODY_TYPE PLUMBING
J 2
(-3325 1825);
DISPLAY 0.872340 (-3325 1825);
PAINT GREEN (-3325 1825);
DISPLAY INVISIBLE (-3325 1825);
FORCEPROP 1 LAST HDL_TAP TRUE
J 2
(-3650 1650);
DISPLAY 0.872340 (-3650 1650);
DISPLAY INVISIBLE (-3650 1650);
FORCEPROP 1 LAST PATH I39
J 2
(-3323 1775);
DISPLAY 0.872340 (-3323 1775);
PAINT GREEN (-3323 1775);
DISPLAY INVISIBLE (-3323 1775);
FORCEADD TAP..1
R 2
(-3325 775);
FORCEPROP 3 LASTPIN (-3275 775) SIG_NAME P5E_CPU1_P0_TX_BUF_DN<6>
J 0
(-3265 785);
DISPLAY 0.659574 (-3265 785);
PAINT MONO (-3265 785);
DISPLAY INVISIBLE (-3265 785);
FORCEPROP 1 LASTPIN (-3275 775) BN 6
J 2
(-3263 783);
DISPLAY 0.680851 (-3263 783);
PAINT GREEN (-3263 783);
FORCEPROP 2 LAST CDS_LIB standard
J 0
(-3325 775);
DISPLAY INVISIBLE (-3325 775);
FORCEPROP 1 LAST BODY_TYPE PLUMBING
J 2
(-3325 825);
DISPLAY 0.872340 (-3325 825);
PAINT GREEN (-3325 825);
DISPLAY INVISIBLE (-3325 825);
FORCEPROP 1 LAST HDL_TAP TRUE
J 2
(-3650 650);
DISPLAY 0.872340 (-3650 650);
DISPLAY INVISIBLE (-3650 650);
FORCEPROP 1 LAST PATH I4
J 2
(-3323 775);
DISPLAY 0.872340 (-3323 775);
PAINT GREEN (-3323 775);
DISPLAY INVISIBLE (-3323 775);
FORCEADD TAP..1
R 2
(-3325 1975);
FORCEPROP 3 LASTPIN (-3275 1975) SIG_NAME P5E_CPU1_P0_TX_BUF_DN<0>
J 0
(-3265 1985);
DISPLAY 0.659574 (-3265 1985);
PAINT MONO (-3265 1985);
DISPLAY INVISIBLE (-3265 1985);
FORCEPROP 1 LASTPIN (-3275 1975) BN 0
J 2
(-3263 1983);
DISPLAY 0.680851 (-3263 1983);
PAINT GREEN (-3263 1983);
FORCEPROP 2 LAST CDS_LIB standard
J 0
(-3325 1975);
DISPLAY INVISIBLE (-3325 1975);
FORCEPROP 1 LAST BODY_TYPE PLUMBING
J 2
(-3325 2025);
DISPLAY 0.872340 (-3325 2025);
PAINT GREEN (-3325 2025);
DISPLAY INVISIBLE (-3325 2025);
FORCEPROP 1 LAST HDL_TAP TRUE
J 2
(-3650 1850);
DISPLAY 0.872340 (-3650 1850);
DISPLAY INVISIBLE (-3650 1850);
FORCEPROP 1 LAST PATH I40
J 2
(-3323 1975);
DISPLAY 0.872340 (-3323 1975);
PAINT GREEN (-3323 1975);
DISPLAY INVISIBLE (-3323 1975);
FORCEADD TAP..1
R 2
(-3075 1825);
FORCEPROP 3 LASTPIN (-3025 1825) SIG_NAME P5E_CPU1_P0_TX_BUF_DP<1>
J 0
(-3015 1835);
DISPLAY 0.659574 (-3015 1835);
PAINT MONO (-3015 1835);
DISPLAY INVISIBLE (-3015 1835);
FORCEPROP 1 LASTPIN (-3025 1825) BN 1
J 2
(-3013 1833);
DISPLAY 0.680851 (-3013 1833);
PAINT GREEN (-3013 1833);
FORCEPROP 2 LAST CDS_LIB standard
J 0
(-3075 1825);
DISPLAY INVISIBLE (-3075 1825);
FORCEPROP 1 LAST BODY_TYPE PLUMBING
J 2
(-3075 1875);
DISPLAY 0.872340 (-3075 1875);
PAINT GREEN (-3075 1875);
DISPLAY INVISIBLE (-3075 1875);
FORCEPROP 1 LAST HDL_TAP TRUE
J 2
(-3400 1700);
DISPLAY 0.872340 (-3400 1700);
DISPLAY INVISIBLE (-3400 1700);
FORCEPROP 1 LAST PATH I41
J 2
(-3073 1825);
DISPLAY 0.872340 (-3073 1825);
PAINT GREEN (-3073 1825);
DISPLAY INVISIBLE (-3073 1825);
FORCEADD TAP..1
R 2
(-3075 2025);
FORCEPROP 3 LASTPIN (-3025 2025) SIG_NAME P5E_CPU1_P0_TX_BUF_DP<0>
J 0
(-3015 2035);
DISPLAY 0.659574 (-3015 2035);
PAINT MONO (-3015 2035);
DISPLAY INVISIBLE (-3015 2035);
FORCEPROP 1 LASTPIN (-3025 2025) BN 0
J 2
(-3013 2033);
DISPLAY 0.680851 (-3013 2033);
PAINT GREEN (-3013 2033);
FORCEPROP 2 LAST CDS_LIB standard
J 0
(-3075 2025);
DISPLAY INVISIBLE (-3075 2025);
FORCEPROP 1 LAST BODY_TYPE PLUMBING
J 2
(-3075 2075);
DISPLAY 0.872340 (-3075 2075);
PAINT GREEN (-3075 2075);
DISPLAY INVISIBLE (-3075 2075);
FORCEPROP 1 LAST HDL_TAP TRUE
J 2
(-3400 1900);
DISPLAY 0.872340 (-3400 1900);
DISPLAY INVISIBLE (-3400 1900);
FORCEPROP 1 LAST PATH I42
J 2
(-3073 2025);
DISPLAY 0.872340 (-3073 2025);
PAINT GREEN (-3073 2025);
DISPLAY INVISIBLE (-3073 2025);
FORCEADD PT5161LRS..10
(-7700 4475);
FORCEPROP 1 LAST LOCATION U6014
J 0
(-8050 6100);
DISPLAY 0.723404 (-8050 6100);
PAINT GREEN (-8050 6100);
FORCEPROP 0 LAST $SEC 10
J 0
(-8050 6250);
DISPLAY 0.680851 (-8050 6250);
PAINT MONO (-8050 6250);
DISPLAY INVISIBLE (-8050 6250);
FORCEPROP 0 LAST CDS_SEC 10
J 0
(-8050 6250);
DISPLAY 0.680851 (-8050 6250);
DISPLAY INVISIBLE (-8050 6250);
FORCEPROP 0 LASTPIN (-7250 5625) $PN P10
J 0
(-7240 5635);
DISPLAY 0.680851 (-7240 5635);
PAINT MONO (-7240 5635);
FORCEPROP 0 LASTPIN (-7250 5275) $PN AA10
J 0
(-7240 5285);
DISPLAY 0.680851 (-7240 5285);
PAINT MONO (-7240 5285);
FORCEPROP 0 LASTPIN (-7250 4925) $PN AH10
J 0
(-7240 4935);
DISPLAY 0.680851 (-7240 4935);
PAINT MONO (-7240 4935);
FORCEPROP 0 LASTPIN (-7250 4575) $PN AR10
J 0
(-7240 4585);
DISPLAY 0.680851 (-7240 4585);
PAINT MONO (-7240 4585);
FORCEPROP 0 LASTPIN (-7250 4225) $PN BB10
J 0
(-7240 4235);
DISPLAY 0.680851 (-7240 4235);
PAINT MONO (-7240 4235);
FORCEPROP 0 LASTPIN (-7250 3875) $PN BJ10
J 0
(-7240 3885);
DISPLAY 0.680851 (-7240 3885);
PAINT MONO (-7240 3885);
FORCEPROP 0 LASTPIN (-7250 3525) $PN BT10
J 0
(-7240 3535);
DISPLAY 0.680851 (-7240 3535);
PAINT MONO (-7240 3535);
FORCEPROP 0 LASTPIN (-7250 3175) $PN CC10
J 0
(-7240 3185);
DISPLAY 0.680851 (-7240 3185);
PAINT MONO (-7240 3185);
FORCEPROP 0 LASTPIN (-7250 5725) $PN M7
J 0
(-7240 5735);
DISPLAY 0.680851 (-7240 5735);
PAINT MONO (-7240 5735);
FORCEPROP 0 LASTPIN (-7250 5375) $PN W7
J 0
(-7240 5385);
DISPLAY 0.680851 (-7240 5385);
PAINT MONO (-7240 5385);
FORCEPROP 0 LASTPIN (-7250 5025) $PN AF7
J 0
(-7240 5035);
DISPLAY 0.680851 (-7240 5035);
PAINT MONO (-7240 5035);
FORCEPROP 0 LASTPIN (-7250 4675) $PN AN7
J 0
(-7240 4685);
DISPLAY 0.680851 (-7240 4685);
PAINT MONO (-7240 4685);
FORCEPROP 0 LASTPIN (-7250 4325) $PN AY7
J 0
(-7240 4335);
DISPLAY 0.680851 (-7240 4335);
PAINT MONO (-7240 4335);
FORCEPROP 0 LASTPIN (-7250 3975) $PN BG7
J 0
(-7240 3985);
DISPLAY 0.680851 (-7240 3985);
PAINT MONO (-7240 3985);
FORCEPROP 0 LASTPIN (-7250 3625) $PN BP7
J 0
(-7240 3635);
DISPLAY 0.680851 (-7240 3635);
PAINT MONO (-7240 3635);
FORCEPROP 0 LASTPIN (-7250 3275) $PN CA7
J 0
(-7240 3285);
DISPLAY 0.680851 (-7240 3285);
PAINT MONO (-7240 3285);
FORCEPROP 2 LAST PART_TYPE SMLF
J 0
(-8050 6200);
DISPLAY 0.680851 (-8050 6200);
FORCEPROP 2 LAST VALUE PT5161LRS
J 0
(-8050 6150);
DISPLAY 0.680851 (-8050 6150);
FORCEPROP 1 LAST MATERIAL IC
J 0
(-8050 5950);
DISPLAY 0.723404 (-8050 5950);
PAINT GREEN (-8050 5950);
FORCEPROP 1 LAST NEEDS_NO_SIZE TRUE
J 0
(-7700 4475);
DISPLAY 0.723404 (-7700 4475);
PAINT GREEN (-7700 4475);
DISPLAY INVISIBLE (-7700 4475);
FORCEPROP 1 LAST CDS_LMAN_SYM_OUTLINE -350,1450,300,-1400
J 0
(-7700 4475);
DISPLAY 0.468085 (-7700 4475);
PAINT GREEN (-7700 4475);
DISPLAY INVISIBLE (-7700 4475);
FORCEPROP 2 LAST CDS_LIB pure_quanta
J 0
(-7700 4475);
DISPLAY INVISIBLE (-7700 4475);
FORCEPROP 1 LAST PATH I43
J 0
(-7700 4475);
DISPLAY 0.723404 (-7700 4475);
PAINT GREEN (-7700 4475);
DISPLAY INVISIBLE (-7700 4475);
FORCEPROP 1 LAST PART_NUMBER AJ051610U03
J 0
(-8050 6025);
DISPLAY 0.723404 (-8050 6025);
PAINT GREEN (-8050 6025);
DISPLAY INVISIBLE (-8050 6025);
FORCEADD Q_CAP_DIFFBUS..2
R 2
(-2350 1775);
FORCEPROP 1 LAST LOCATION C6632
J 2
(-2050 1775);
DISPLAY 0.723404 (-2050 1775);
PAINT GREEN (-2050 1775);
FORCEPROP 2 LAST $SEC 1
J 2
(-2175 1850);
DISPLAY 0.680851 (-2175 1850);
PAINT MONO (-2175 1850);
DISPLAY INVISIBLE (-2175 1850);
FORCEPROP 2 LAST CDS_SEC 1
J 2
(-2175 1850);
DISPLAY 0.680851 (-2175 1850);
DISPLAY INVISIBLE (-2175 1850);
FORCEPROP 2 LASTPIN (-2275 1775) $PN 1
J 0
(-2265 1785);
DISPLAY 0.808511 (-2265 1785);
FORCEPROP 2 LASTPIN (-2425 1775) $PN 2
J 2
(-2435 1785);
DISPLAY 0.808511 (-2435 1785);
FORCEPROP 2 LAST VALUE DIFF BUS_0.22UF
J 2
(-2500 1775);
DISPLAY 0.553191 (-2500 1775);
FORCEPROP 2 LAST TOLERANCE 20%
J 2
(-2425 1825);
DISPLAY 0.553191 (-2425 1825);
DISPLAY INVISIBLE (-2425 1825);
FORCEPROP 2 LAST PACK_TYPE C0201
J 2
(-2525 1825);
DISPLAY 0.553191 (-2525 1825);
DISPLAY INVISIBLE (-2525 1825);
FORCEPROP 1 LAST MATERIAL X6S
J 2
(-2341 1854);
DISPLAY 0.574468 (-2341 1854);
PAINT GREEN (-2341 1854);
DISPLAY INVISIBLE (-2341 1854);
FORCEPROP 2 LAST VOLTAGE 6.3V
J 2
(-2700 1825);
DISPLAY 0.553191 (-2700 1825);
DISPLAY INVISIBLE (-2700 1825);
FORCEPROP 1 LAST PIN_NAMES_ROTATE TRUE
J 2
(-2350 1775);
DISPLAY 0.489362 (-2350 1775);
PAINT GREEN (-2350 1775);
DISPLAY INVISIBLE (-2350 1775);
FORCEPROP 2 LAST CDS_LIB pure_quanta
J 2
(-2350 1775);
DISPLAY INVISIBLE (-2350 1775);
FORCEPROP 1 LAST CDS_LMAN_SYM_OUTLINE -25,50,25,-50
J 2
(-2350 1775);
DISPLAY 0.468085 (-2350 1775);
PAINT GREEN (-2350 1775);
DISPLAY INVISIBLE (-2350 1775);
FORCEPROP 1 LAST PATH I44
J 2
(-2350 1775);
DISPLAY 0.723404 (-2350 1775);
DISPLAY INVISIBLE (-2350 1775);
FORCEPROP 1 LAST PART_NUMBER SP_CH4221MEE01
J 2
(-2466 1863);
DISPLAY 0.574468 (-2466 1863);
PAINT GREEN (-2466 1863);
DISPLAY INVISIBLE (-2466 1863);
FORCEPROP 1 LAST LOCATION C6632
J 0
(-2100 1850);
DISPLAY 1.021277 (-2100 1850);
DISPLAY INVISIBLE (-2100 1850);
FORCEADD Q_CAP_DIFFBUS..2
R 2
(-2350 1825);
FORCEPROP 1 LAST LOCATION C6631
J 2
(-2050 1825);
DISPLAY 0.723404 (-2050 1825);
PAINT GREEN (-2050 1825);
FORCEPROP 2 LAST $SEC 1
J 2
(-2175 1900);
DISPLAY 0.680851 (-2175 1900);
PAINT MONO (-2175 1900);
DISPLAY INVISIBLE (-2175 1900);
FORCEPROP 2 LAST CDS_SEC 1
J 2
(-2175 1900);
DISPLAY 0.680851 (-2175 1900);
DISPLAY INVISIBLE (-2175 1900);
FORCEPROP 2 LASTPIN (-2275 1825) $PN 1
J 0
(-2265 1835);
DISPLAY 0.808511 (-2265 1835);
FORCEPROP 2 LASTPIN (-2425 1825) $PN 2
J 2
(-2435 1835);
DISPLAY 0.808511 (-2435 1835);
FORCEPROP 2 LAST VALUE DIFF BUS_0.22UF
J 2
(-2500 1825);
DISPLAY 0.553191 (-2500 1825);
FORCEPROP 2 LAST TOLERANCE 20%
J 2
(-2425 1875);
DISPLAY 0.553191 (-2425 1875);
DISPLAY INVISIBLE (-2425 1875);
FORCEPROP 2 LAST PACK_TYPE C0201
J 2
(-2525 1875);
DISPLAY 0.553191 (-2525 1875);
DISPLAY INVISIBLE (-2525 1875);
FORCEPROP 1 LAST MATERIAL X6S
J 2
(-2341 1904);
DISPLAY 0.574468 (-2341 1904);
PAINT GREEN (-2341 1904);
DISPLAY INVISIBLE (-2341 1904);
FORCEPROP 2 LAST VOLTAGE 6.3V
J 2
(-2700 1875);
DISPLAY 0.553191 (-2700 1875);
DISPLAY INVISIBLE (-2700 1875);
FORCEPROP 1 LAST PIN_NAMES_ROTATE TRUE
J 2
(-2350 1825);
DISPLAY 0.489362 (-2350 1825);
PAINT GREEN (-2350 1825);
DISPLAY INVISIBLE (-2350 1825);
FORCEPROP 2 LAST CDS_LIB pure_quanta
J 2
(-2350 1825);
DISPLAY INVISIBLE (-2350 1825);
FORCEPROP 1 LAST CDS_LMAN_SYM_OUTLINE -25,50,25,-50
J 2
(-2350 1825);
DISPLAY 0.468085 (-2350 1825);
PAINT GREEN (-2350 1825);
DISPLAY INVISIBLE (-2350 1825);
FORCEPROP 1 LAST PATH I45
J 2
(-2350 1825);
DISPLAY 0.723404 (-2350 1825);
DISPLAY INVISIBLE (-2350 1825);
FORCEPROP 1 LAST PART_NUMBER SP_CH4221MEE01
J 2
(-2466 1913);
DISPLAY 0.574468 (-2466 1913);
PAINT GREEN (-2466 1913);
DISPLAY INVISIBLE (-2466 1913);
FORCEPROP 1 LAST LOCATION C6631
J 0
(-2100 1900);
DISPLAY 1.021277 (-2100 1900);
DISPLAY INVISIBLE (-2100 1900);
FORCEADD Q_CAP_DIFFBUS..2
R 2
(-2350 2025);
FORCEPROP 1 LAST LOCATION C6629
J 2
(-2050 2025);
DISPLAY 0.723404 (-2050 2025);
PAINT GREEN (-2050 2025);
FORCEPROP 2 LAST $SEC 1
J 2
(-2175 2100);
DISPLAY 0.680851 (-2175 2100);
PAINT MONO (-2175 2100);
DISPLAY INVISIBLE (-2175 2100);
FORCEPROP 2 LAST CDS_SEC 1
J 2
(-2175 2100);
DISPLAY 0.680851 (-2175 2100);
DISPLAY INVISIBLE (-2175 2100);
FORCEPROP 2 LASTPIN (-2275 2025) $PN 1
J 0
(-2265 2035);
DISPLAY 0.808511 (-2265 2035);
FORCEPROP 2 LASTPIN (-2425 2025) $PN 2
J 2
(-2435 2035);
DISPLAY 0.808511 (-2435 2035);
FORCEPROP 1 LAST MATERIAL X6S
J 2
(-2441 2229);
DISPLAY 0.574468 (-2441 2229);
PAINT GREEN (-2441 2229);
FORCEPROP 2 LAST TOLERANCE 20%
J 2
(-2300 2175);
DISPLAY 0.553191 (-2300 2175);
PAINT GREEN (-2300 2175);
FORCEPROP 2 LAST VOLTAGE 6.3V
J 2
(-2175 2175);
DISPLAY 0.553191 (-2175 2175);
PAINT GREEN (-2175 2175);
FORCEPROP 2 LAST VALUE DIFF BUS_0.22UF
J 2
(-2500 2025);
DISPLAY 0.553191 (-2500 2025);
FORCEPROP 2 LAST PACK_TYPE C0201
J 2
(-2400 2175);
DISPLAY 0.553191 (-2400 2175);
PAINT GREEN (-2400 2175);
FORCEPROP 1 LAST PIN_NAMES_ROTATE TRUE
J 2
(-2350 2025);
DISPLAY 0.489362 (-2350 2025);
PAINT GREEN (-2350 2025);
DISPLAY INVISIBLE (-2350 2025);
FORCEPROP 1 LAST CDS_LMAN_SYM_OUTLINE -25,50,25,-50
J 2
(-2350 2025);
DISPLAY 0.468085 (-2350 2025);
PAINT GREEN (-2350 2025);
DISPLAY INVISIBLE (-2350 2025);
FORCEPROP 2 LAST CDS_LIB pure_quanta
J 2
(-2350 2025);
DISPLAY INVISIBLE (-2350 2025);
FORCEPROP 1 LAST PATH I46
J 2
(-2350 2025);
DISPLAY 0.723404 (-2350 2025);
DISPLAY INVISIBLE (-2350 2025);
FORCEPROP 1 LAST PART_NUMBER SP_CH4221MEE01
J 2
(-2166 2113);
DISPLAY 0.574468 (-2166 2113);
PAINT GREEN (-2166 2113);
DISPLAY INVISIBLE (-2166 2113);
FORCEPROP 1 LAST LOCATION C6629
J 0
(-2100 2100);
DISPLAY 1.021277 (-2100 2100);
DISPLAY INVISIBLE (-2100 2100);
FORCEADD Q_CAP_DIFFBUS..2
R 2
(-2350 1975);
FORCEPROP 1 LAST LOCATION C6630
J 2
(-2050 1975);
DISPLAY 0.723404 (-2050 1975);
PAINT GREEN (-2050 1975);
FORCEPROP 2 LAST $SEC 1
J 2
(-2175 2050);
DISPLAY 0.680851 (-2175 2050);
PAINT MONO (-2175 2050);
DISPLAY INVISIBLE (-2175 2050);
FORCEPROP 2 LAST CDS_SEC 1
J 2
(-2175 2050);
DISPLAY 0.680851 (-2175 2050);
DISPLAY INVISIBLE (-2175 2050);
FORCEPROP 2 LASTPIN (-2275 1975) $PN 1
J 0
(-2265 1985);
DISPLAY 0.808511 (-2265 1985);
FORCEPROP 2 LASTPIN (-2425 1975) $PN 2
J 2
(-2435 1985);
DISPLAY 0.808511 (-2435 1985);
FORCEPROP 2 LAST VALUE DIFF BUS_0.22UF
J 2
(-2500 1975);
DISPLAY 0.553191 (-2500 1975);
FORCEPROP 2 LAST TOLERANCE 20%
J 2
(-2425 2025);
DISPLAY 0.553191 (-2425 2025);
DISPLAY INVISIBLE (-2425 2025);
FORCEPROP 2 LAST PACK_TYPE C0201
J 2
(-2525 2025);
DISPLAY 0.553191 (-2525 2025);
DISPLAY INVISIBLE (-2525 2025);
FORCEPROP 1 LAST MATERIAL X6S
J 2
(-2341 2054);
DISPLAY 0.574468 (-2341 2054);
PAINT GREEN (-2341 2054);
DISPLAY INVISIBLE (-2341 2054);
FORCEPROP 2 LAST VOLTAGE 6.3V
J 2
(-2700 2025);
DISPLAY 0.553191 (-2700 2025);
DISPLAY INVISIBLE (-2700 2025);
FORCEPROP 1 LAST PIN_NAMES_ROTATE TRUE
J 2
(-2350 1975);
DISPLAY 0.489362 (-2350 1975);
PAINT GREEN (-2350 1975);
DISPLAY INVISIBLE (-2350 1975);
FORCEPROP 2 LAST CDS_LIB pure_quanta
J 2
(-2350 1975);
DISPLAY INVISIBLE (-2350 1975);
FORCEPROP 1 LAST CDS_LMAN_SYM_OUTLINE -25,50,25,-50
J 2
(-2350 1975);
DISPLAY 0.468085 (-2350 1975);
PAINT GREEN (-2350 1975);
DISPLAY INVISIBLE (-2350 1975);
FORCEPROP 1 LAST PATH I47
J 2
(-2350 1975);
DISPLAY 0.723404 (-2350 1975);
DISPLAY INVISIBLE (-2350 1975);
FORCEPROP 1 LAST PART_NUMBER SP_CH4221MEE01
J 2
(-2466 2063);
DISPLAY 0.574468 (-2466 2063);
PAINT GREEN (-2466 2063);
DISPLAY INVISIBLE (-2466 2063);
FORCEPROP 1 LAST LOCATION C6630
J 0
(-2100 2050);
DISPLAY 1.021277 (-2100 2050);
DISPLAY INVISIBLE (-2100 2050);
FORCEADD TAP..1
(-1800 1825);
FORCEPROP 3 LASTPIN (-1850 1825) SIG_NAME P5E_CPU1_P0_TX_BUF_C_DP<1>
J 0
(-1840 1835);
DISPLAY 0.659574 (-1840 1835);
PAINT MONO (-1840 1835);
DISPLAY INVISIBLE (-1840 1835);
FORCEPROP 1 LASTPIN (-1850 1825) BN 1
J 0
(-1862 1833);
DISPLAY 0.680851 (-1862 1833);
PAINT GREEN (-1862 1833);
FORCEPROP 2 LAST CDS_LIB standard
J 0
(-1800 1825);
DISPLAY INVISIBLE (-1800 1825);
FORCEPROP 1 LAST BODY_TYPE PLUMBING
J 0
(-1800 1875);
DISPLAY 0.872340 (-1800 1875);
PAINT GREEN (-1800 1875);
DISPLAY INVISIBLE (-1800 1875);
FORCEPROP 1 LAST HDL_TAP TRUE
J 0
(-1475 1700);
DISPLAY 0.872340 (-1475 1700);
DISPLAY INVISIBLE (-1475 1700);
FORCEPROP 1 LAST PATH I48
J 0
(-1802 1825);
DISPLAY 0.872340 (-1802 1825);
PAINT GREEN (-1802 1825);
DISPLAY INVISIBLE (-1802 1825);
FORCEADD TAP..1
(-1800 2025);
FORCEPROP 3 LASTPIN (-1850 2025) SIG_NAME P5E_CPU1_P0_TX_BUF_C_DP<0>
J 0
(-1840 2035);
DISPLAY 0.659574 (-1840 2035);
PAINT MONO (-1840 2035);
DISPLAY INVISIBLE (-1840 2035);
FORCEPROP 1 LASTPIN (-1850 2025) BN 0
J 0
(-1862 2033);
DISPLAY 0.680851 (-1862 2033);
PAINT GREEN (-1862 2033);
FORCEPROP 2 LAST CDS_LIB standard
J 0
(-1800 2025);
DISPLAY INVISIBLE (-1800 2025);
FORCEPROP 1 LAST BODY_TYPE PLUMBING
J 0
(-1800 2075);
DISPLAY 0.872340 (-1800 2075);
PAINT GREEN (-1800 2075);
DISPLAY INVISIBLE (-1800 2075);
FORCEPROP 1 LAST HDL_TAP TRUE
J 0
(-1475 1900);
DISPLAY 0.872340 (-1475 1900);
DISPLAY INVISIBLE (-1475 1900);
FORCEPROP 1 LAST PATH I49
J 0
(-1802 2025);
DISPLAY 0.872340 (-1802 2025);
PAINT GREEN (-1802 2025);
DISPLAY INVISIBLE (-1802 2025);
FORCEADD TAP..1
R 2
(-3325 975);
FORCEPROP 3 LASTPIN (-3275 975) SIG_NAME P5E_CPU1_P0_TX_BUF_DN<5>
J 0
(-3265 985);
DISPLAY 0.659574 (-3265 985);
PAINT MONO (-3265 985);
DISPLAY INVISIBLE (-3265 985);
FORCEPROP 1 LASTPIN (-3275 975) BN 5
J 2
(-3263 983);
DISPLAY 0.680851 (-3263 983);
PAINT GREEN (-3263 983);
FORCEPROP 2 LAST CDS_LIB standard
J 0
(-3325 975);
DISPLAY INVISIBLE (-3325 975);
FORCEPROP 1 LAST BODY_TYPE PLUMBING
J 2
(-3325 1025);
DISPLAY 0.872340 (-3325 1025);
PAINT GREEN (-3325 1025);
DISPLAY INVISIBLE (-3325 1025);
FORCEPROP 1 LAST HDL_TAP TRUE
J 2
(-3650 850);
DISPLAY 0.872340 (-3650 850);
DISPLAY INVISIBLE (-3650 850);
FORCEPROP 1 LAST PATH I5
J 2
(-3323 975);
DISPLAY 0.872340 (-3323 975);
PAINT GREEN (-3323 975);
DISPLAY INVISIBLE (-3323 975);
FORCEADD TAP..1
(-1600 1775);
FORCEPROP 3 LASTPIN (-1650 1775) SIG_NAME P5E_CPU1_P0_TX_BUF_C_DN<1>
J 0
(-1640 1785);
DISPLAY 0.659574 (-1640 1785);
PAINT MONO (-1640 1785);
DISPLAY INVISIBLE (-1640 1785);
FORCEPROP 1 LASTPIN (-1650 1775) BN 1
J 0
(-1662 1783);
DISPLAY 0.680851 (-1662 1783);
PAINT GREEN (-1662 1783);
FORCEPROP 2 LAST CDS_LIB standard
J 0
(-1600 1775);
DISPLAY INVISIBLE (-1600 1775);
FORCEPROP 1 LAST BODY_TYPE PLUMBING
J 0
(-1600 1825);
DISPLAY 0.872340 (-1600 1825);
PAINT GREEN (-1600 1825);
DISPLAY INVISIBLE (-1600 1825);
FORCEPROP 1 LAST HDL_TAP TRUE
J 0
(-1275 1650);
DISPLAY 0.872340 (-1275 1650);
DISPLAY INVISIBLE (-1275 1650);
FORCEPROP 1 LAST PATH I50
J 0
(-1602 1775);
DISPLAY 0.872340 (-1602 1775);
PAINT GREEN (-1602 1775);
DISPLAY INVISIBLE (-1602 1775);
FORCEADD TAP..1
(-1600 1975);
FORCEPROP 3 LASTPIN (-1650 1975) SIG_NAME P5E_CPU1_P0_TX_BUF_C_DN<0>
J 0
(-1640 1985);
DISPLAY 0.659574 (-1640 1985);
PAINT MONO (-1640 1985);
DISPLAY INVISIBLE (-1640 1985);
FORCEPROP 1 LASTPIN (-1650 1975) BN 0
J 0
(-1662 1983);
DISPLAY 0.680851 (-1662 1983);
PAINT GREEN (-1662 1983);
FORCEPROP 2 LAST CDS_LIB standard
J 0
(-1600 1975);
DISPLAY INVISIBLE (-1600 1975);
FORCEPROP 1 LAST BODY_TYPE PLUMBING
J 0
(-1600 2025);
DISPLAY 0.872340 (-1600 2025);
PAINT GREEN (-1600 2025);
DISPLAY INVISIBLE (-1600 2025);
FORCEPROP 1 LAST HDL_TAP TRUE
J 0
(-1275 1850);
DISPLAY 0.872340 (-1275 1850);
DISPLAY INVISIBLE (-1275 1850);
FORCEPROP 1 LAST PATH I51
J 0
(-1602 1975);
DISPLAY 0.872340 (-1602 1975);
PAINT GREEN (-1602 1975);
DISPLAY INVISIBLE (-1602 1975);
FORCEADD TAP..1
(-6775 3175);
FORCEPROP 3 LASTPIN (-6825 3175) SIG_NAME P5E_CPU1_P0_TX_BUF_DN<8>
J 0
(-6815 3185);
DISPLAY 0.659574 (-6815 3185);
PAINT MONO (-6815 3185);
DISPLAY INVISIBLE (-6815 3185);
FORCEPROP 1 LASTPIN (-6825 3175) BN 8
J 0
(-6837 3183);
DISPLAY 0.680851 (-6837 3183);
PAINT GREEN (-6837 3183);
FORCEPROP 2 LAST CDS_LIB standard
J 0
(-6775 3175);
DISPLAY INVISIBLE (-6775 3175);
FORCEPROP 1 LAST BODY_TYPE PLUMBING
J 0
(-6775 3225);
DISPLAY 0.872340 (-6775 3225);
PAINT GREEN (-6775 3225);
DISPLAY INVISIBLE (-6775 3225);
FORCEPROP 1 LAST HDL_TAP TRUE
J 0
(-6450 3050);
DISPLAY 0.872340 (-6450 3050);
DISPLAY INVISIBLE (-6450 3050);
FORCEPROP 1 LAST PATH I52
J 0
(-6777 3175);
DISPLAY 0.872340 (-6777 3175);
PAINT GREEN (-6777 3175);
DISPLAY INVISIBLE (-6777 3175);
FORCEADD TAP..1
(-6975 3275);
FORCEPROP 3 LASTPIN (-7025 3275) SIG_NAME P5E_CPU1_P0_TX_BUF_DP<8>
J 0
(-7015 3285);
DISPLAY 0.659574 (-7015 3285);
PAINT MONO (-7015 3285);
DISPLAY INVISIBLE (-7015 3285);
FORCEPROP 1 LASTPIN (-7025 3275) BN 8
J 0
(-7037 3283);
DISPLAY 0.680851 (-7037 3283);
PAINT GREEN (-7037 3283);
FORCEPROP 2 LAST CDS_LIB standard
J 0
(-6975 3275);
DISPLAY INVISIBLE (-6975 3275);
FORCEPROP 1 LAST BODY_TYPE PLUMBING
J 0
(-6975 3325);
DISPLAY 0.872340 (-6975 3325);
PAINT GREEN (-6975 3325);
DISPLAY INVISIBLE (-6975 3325);
FORCEPROP 1 LAST HDL_TAP TRUE
J 0
(-6650 3150);
DISPLAY 0.872340 (-6650 3150);
DISPLAY INVISIBLE (-6650 3150);
FORCEPROP 1 LAST PATH I53
J 0
(-6977 3275);
DISPLAY 0.872340 (-6977 3275);
PAINT GREEN (-6977 3275);
DISPLAY INVISIBLE (-6977 3275);
FORCEADD TAP..1
(-6775 3525);
FORCEPROP 3 LASTPIN (-6825 3525) SIG_NAME P5E_CPU1_P0_TX_BUF_DN<9>
J 0
(-6815 3535);
DISPLAY 0.659574 (-6815 3535);
PAINT MONO (-6815 3535);
DISPLAY INVISIBLE (-6815 3535);
FORCEPROP 1 LASTPIN (-6825 3525) BN 9
J 0
(-6837 3533);
DISPLAY 0.680851 (-6837 3533);
PAINT GREEN (-6837 3533);
FORCEPROP 2 LAST CDS_LIB standard
J 0
(-6775 3525);
DISPLAY INVISIBLE (-6775 3525);
FORCEPROP 1 LAST BODY_TYPE PLUMBING
J 0
(-6775 3575);
DISPLAY 0.872340 (-6775 3575);
PAINT GREEN (-6775 3575);
DISPLAY INVISIBLE (-6775 3575);
FORCEPROP 1 LAST HDL_TAP TRUE
J 0
(-6450 3400);
DISPLAY 0.872340 (-6450 3400);
DISPLAY INVISIBLE (-6450 3400);
FORCEPROP 1 LAST PATH I54
J 0
(-6777 3525);
DISPLAY 0.872340 (-6777 3525);
PAINT GREEN (-6777 3525);
DISPLAY INVISIBLE (-6777 3525);
FORCEADD TAP..1
(-6975 3625);
FORCEPROP 3 LASTPIN (-7025 3625) SIG_NAME P5E_CPU1_P0_TX_BUF_DP<9>
J 0
(-7015 3635);
DISPLAY 0.659574 (-7015 3635);
PAINT MONO (-7015 3635);
DISPLAY INVISIBLE (-7015 3635);
FORCEPROP 1 LASTPIN (-7025 3625) BN 9
J 0
(-7037 3633);
DISPLAY 0.680851 (-7037 3633);
PAINT GREEN (-7037 3633);
FORCEPROP 2 LAST CDS_LIB standard
J 0
(-6975 3625);
DISPLAY INVISIBLE (-6975 3625);
FORCEPROP 1 LAST BODY_TYPE PLUMBING
J 0
(-6975 3675);
DISPLAY 0.872340 (-6975 3675);
PAINT GREEN (-6975 3675);
DISPLAY INVISIBLE (-6975 3675);
FORCEPROP 1 LAST HDL_TAP TRUE
J 0
(-6650 3500);
DISPLAY 0.872340 (-6650 3500);
DISPLAY INVISIBLE (-6650 3500);
FORCEPROP 1 LAST PATH I55
J 0
(-6977 3625);
DISPLAY 0.872340 (-6977 3625);
PAINT GREEN (-6977 3625);
DISPLAY INVISIBLE (-6977 3625);
FORCEADD OFFPAGE..2
(-600 2000);
FORCEPROP 2 LAST $XR0 122 
J 0
(-411 2000);
DISPLAY 0.638298 (-411 2000);
PAINT MONO (-411 2000);
FORCEPROP 2 LAST CDS_LIB standard
J 0
(-600 2000);
DISPLAY INVISIBLE (-600 2000);
FORCEPROP 1 LAST OFFPAGE TRUE
J 0
(-275 1875);
DISPLAY 0.872340 (-275 1875);
DISPLAY INVISIBLE (-275 1875);
FORCEPROP 1 LAST COMMENT_BODY TRUE
J 0
(-645 1905);
DISPLAY 0.872340 (-645 1905);
PAINT GREEN (-645 1905);
DISPLAY INVISIBLE (-645 1905);
FORCEPROP 2 LAST PATH I56
J 0
(-400 2050);
DISPLAY 0.680851 (-400 2050);
DISPLAY INVISIBLE (-400 2050);
FORCEADD OFFPAGE..2
(-600 2050);
FORCEPROP 2 LAST $XR0 122 
J 0
(-411 2050);
DISPLAY 0.638298 (-411 2050);
PAINT MONO (-411 2050);
FORCEPROP 2 LAST CDS_LIB standard
J 0
(-600 2050);
DISPLAY INVISIBLE (-600 2050);
FORCEPROP 1 LAST OFFPAGE TRUE
J 0
(-275 1925);
DISPLAY 0.872340 (-275 1925);
DISPLAY INVISIBLE (-275 1925);
FORCEPROP 1 LAST COMMENT_BODY TRUE
J 0
(-645 1955);
DISPLAY 0.872340 (-645 1955);
PAINT GREEN (-645 1955);
DISPLAY INVISIBLE (-645 1955);
FORCEPROP 2 LAST PATH I57
J 0
(-400 2100);
DISPLAY 0.680851 (-400 2100);
DISPLAY INVISIBLE (-400 2100);
FORCEADD OFFPAGE..1
(-8875 2075);
FORCEPROP 2 LAST $XR0 320 
J 0
(-9127 2075);
DISPLAY 0.638298 (-9127 2075);
PAINT MONO (-9127 2075);
FORCEPROP 2 LAST CDS_LIB standard
J 0
(-8875 2075);
DISPLAY INVISIBLE (-8875 2075);
FORCEPROP 1 LAST OFFPAGE TRUE
J 0
(-8550 1950);
DISPLAY 0.872340 (-8550 1950);
DISPLAY INVISIBLE (-8550 1950);
FORCEPROP 1 LAST COMMENT_BODY TRUE
J 0
(-8750 1975);
DISPLAY 0.872340 (-8750 1975);
PAINT GREEN (-8750 1975);
DISPLAY INVISIBLE (-8750 1975);
FORCEPROP 2 LAST PATH I58
J 0
(-9125 2125);
DISPLAY 0.680851 (-9125 2125);
DISPLAY INVISIBLE (-9125 2125);
FORCEADD OFFPAGE..1
(-8875 2025);
FORCEPROP 2 LAST $XR0 320 
J 0
(-9127 2025);
DISPLAY 0.638298 (-9127 2025);
PAINT MONO (-9127 2025);
FORCEPROP 2 LAST CDS_LIB standard
J 0
(-8875 2025);
DISPLAY INVISIBLE (-8875 2025);
FORCEPROP 1 LAST OFFPAGE TRUE
J 0
(-8550 1900);
DISPLAY 0.872340 (-8550 1900);
DISPLAY INVISIBLE (-8550 1900);
FORCEPROP 1 LAST COMMENT_BODY TRUE
J 0
(-8750 1925);
DISPLAY 0.872340 (-8750 1925);
PAINT GREEN (-8750 1925);
DISPLAY INVISIBLE (-8750 1925);
FORCEPROP 2 LAST PATH I59
J 0
(-9125 2075);
DISPLAY 0.680851 (-9125 2075);
DISPLAY INVISIBLE (-9125 2075);
FORCEADD TAP..1
R 2
(-3325 1175);
FORCEPROP 3 LASTPIN (-3275 1175) SIG_NAME P5E_CPU1_P0_TX_BUF_DN<4>
J 0
(-3265 1185);
DISPLAY 0.659574 (-3265 1185);
PAINT MONO (-3265 1185);
DISPLAY INVISIBLE (-3265 1185);
FORCEPROP 1 LASTPIN (-3275 1175) BN 4
J 2
(-3263 1183);
DISPLAY 0.680851 (-3263 1183);
PAINT GREEN (-3263 1183);
FORCEPROP 2 LAST CDS_LIB standard
J 0
(-3325 1175);
DISPLAY INVISIBLE (-3325 1175);
FORCEPROP 1 LAST BODY_TYPE PLUMBING
J 2
(-3325 1225);
DISPLAY 0.872340 (-3325 1225);
PAINT GREEN (-3325 1225);
DISPLAY INVISIBLE (-3325 1225);
FORCEPROP 1 LAST HDL_TAP TRUE
J 2
(-3650 1050);
DISPLAY 0.872340 (-3650 1050);
DISPLAY INVISIBLE (-3650 1050);
FORCEPROP 1 LAST PATH I6
J 2
(-3323 1175);
DISPLAY 0.872340 (-3323 1175);
PAINT GREEN (-3323 1175);
DISPLAY INVISIBLE (-3323 1175);
FORCEADD TAP..1
(-6775 3875);
FORCEPROP 3 LASTPIN (-6825 3875) SIG_NAME P5E_CPU1_P0_TX_BUF_DN<10>
J 0
(-6815 3885);
DISPLAY 0.659574 (-6815 3885);
PAINT MONO (-6815 3885);
DISPLAY INVISIBLE (-6815 3885);
FORCEPROP 1 LASTPIN (-6825 3875) BN 10
J 0
(-6837 3883);
DISPLAY 0.680851 (-6837 3883);
PAINT GREEN (-6837 3883);
FORCEPROP 2 LAST CDS_LIB standard
J 0
(-6775 3875);
DISPLAY INVISIBLE (-6775 3875);
FORCEPROP 1 LAST BODY_TYPE PLUMBING
J 0
(-6775 3925);
DISPLAY 0.872340 (-6775 3925);
PAINT GREEN (-6775 3925);
DISPLAY INVISIBLE (-6775 3925);
FORCEPROP 1 LAST HDL_TAP TRUE
J 0
(-6450 3750);
DISPLAY 0.872340 (-6450 3750);
DISPLAY INVISIBLE (-6450 3750);
FORCEPROP 1 LAST PATH I60
J 0
(-6777 3875);
DISPLAY 0.872340 (-6777 3875);
PAINT GREEN (-6777 3875);
DISPLAY INVISIBLE (-6777 3875);
FORCEADD TAP..1
(-6975 3975);
FORCEPROP 3 LASTPIN (-7025 3975) SIG_NAME P5E_CPU1_P0_TX_BUF_DP<10>
J 0
(-7015 3985);
DISPLAY 0.659574 (-7015 3985);
PAINT MONO (-7015 3985);
DISPLAY INVISIBLE (-7015 3985);
FORCEPROP 1 LASTPIN (-7025 3975) BN 10
J 0
(-7037 3983);
DISPLAY 0.680851 (-7037 3983);
PAINT GREEN (-7037 3983);
FORCEPROP 2 LAST CDS_LIB standard
J 0
(-6975 3975);
DISPLAY INVISIBLE (-6975 3975);
FORCEPROP 1 LAST BODY_TYPE PLUMBING
J 0
(-6975 4025);
DISPLAY 0.872340 (-6975 4025);
PAINT GREEN (-6975 4025);
DISPLAY INVISIBLE (-6975 4025);
FORCEPROP 1 LAST HDL_TAP TRUE
J 0
(-6650 3850);
DISPLAY 0.872340 (-6650 3850);
DISPLAY INVISIBLE (-6650 3850);
FORCEPROP 1 LAST PATH I61
J 0
(-6977 3975);
DISPLAY 0.872340 (-6977 3975);
PAINT GREEN (-6977 3975);
DISPLAY INVISIBLE (-6977 3975);
FORCEADD TAP..1
(-6775 4225);
FORCEPROP 3 LASTPIN (-6825 4225) SIG_NAME P5E_CPU1_P0_TX_BUF_DN<11>
J 0
(-6815 4235);
DISPLAY 0.659574 (-6815 4235);
PAINT MONO (-6815 4235);
DISPLAY INVISIBLE (-6815 4235);
FORCEPROP 1 LASTPIN (-6825 4225) BN 11
J 0
(-6837 4233);
DISPLAY 0.680851 (-6837 4233);
PAINT GREEN (-6837 4233);
FORCEPROP 2 LAST CDS_LIB standard
J 0
(-6775 4225);
DISPLAY INVISIBLE (-6775 4225);
FORCEPROP 1 LAST BODY_TYPE PLUMBING
J 0
(-6775 4275);
DISPLAY 0.872340 (-6775 4275);
PAINT GREEN (-6775 4275);
DISPLAY INVISIBLE (-6775 4275);
FORCEPROP 1 LAST HDL_TAP TRUE
J 0
(-6450 4100);
DISPLAY 0.872340 (-6450 4100);
DISPLAY INVISIBLE (-6450 4100);
FORCEPROP 1 LAST PATH I62
J 0
(-6777 4225);
DISPLAY 0.872340 (-6777 4225);
PAINT GREEN (-6777 4225);
DISPLAY INVISIBLE (-6777 4225);
FORCEADD TAP..1
(-6975 4325);
FORCEPROP 3 LASTPIN (-7025 4325) SIG_NAME P5E_CPU1_P0_TX_BUF_DP<11>
J 0
(-7015 4335);
DISPLAY 0.659574 (-7015 4335);
PAINT MONO (-7015 4335);
DISPLAY INVISIBLE (-7015 4335);
FORCEPROP 1 LASTPIN (-7025 4325) BN 11
J 0
(-7037 4333);
DISPLAY 0.680851 (-7037 4333);
PAINT GREEN (-7037 4333);
FORCEPROP 2 LAST CDS_LIB standard
J 0
(-6975 4325);
DISPLAY INVISIBLE (-6975 4325);
FORCEPROP 1 LAST BODY_TYPE PLUMBING
J 0
(-6975 4375);
DISPLAY 0.872340 (-6975 4375);
PAINT GREEN (-6975 4375);
DISPLAY INVISIBLE (-6975 4375);
FORCEPROP 1 LAST HDL_TAP TRUE
J 0
(-6650 4200);
DISPLAY 0.872340 (-6650 4200);
DISPLAY INVISIBLE (-6650 4200);
FORCEPROP 1 LAST PATH I63
J 0
(-6977 4325);
DISPLAY 0.872340 (-6977 4325);
PAINT GREEN (-6977 4325);
DISPLAY INVISIBLE (-6977 4325);
FORCEADD TAP..1
(-6975 4675);
FORCEPROP 3 LASTPIN (-7025 4675) SIG_NAME P5E_CPU1_P0_TX_BUF_DP<12>
J 0
(-7015 4685);
DISPLAY 0.659574 (-7015 4685);
PAINT MONO (-7015 4685);
DISPLAY INVISIBLE (-7015 4685);
FORCEPROP 1 LASTPIN (-7025 4675) BN 12
J 0
(-7037 4683);
DISPLAY 0.680851 (-7037 4683);
PAINT GREEN (-7037 4683);
FORCEPROP 2 LAST CDS_LIB standard
J 0
(-6975 4675);
DISPLAY INVISIBLE (-6975 4675);
FORCEPROP 1 LAST BODY_TYPE PLUMBING
J 0
(-6975 4725);
DISPLAY 0.872340 (-6975 4725);
PAINT GREEN (-6975 4725);
DISPLAY INVISIBLE (-6975 4725);
FORCEPROP 1 LAST HDL_TAP TRUE
J 0
(-6650 4550);
DISPLAY 0.872340 (-6650 4550);
DISPLAY INVISIBLE (-6650 4550);
FORCEPROP 1 LAST PATH I64
J 0
(-6977 4675);
DISPLAY 0.872340 (-6977 4675);
PAINT GREEN (-6977 4675);
DISPLAY INVISIBLE (-6977 4675);
FORCEADD TAP..1
(-6775 4575);
FORCEPROP 3 LASTPIN (-6825 4575) SIG_NAME P5E_CPU1_P0_TX_BUF_DN<12>
J 0
(-6815 4585);
DISPLAY 0.659574 (-6815 4585);
PAINT MONO (-6815 4585);
DISPLAY INVISIBLE (-6815 4585);
FORCEPROP 1 LASTPIN (-6825 4575) BN 12
J 0
(-6837 4583);
DISPLAY 0.680851 (-6837 4583);
PAINT GREEN (-6837 4583);
FORCEPROP 2 LAST CDS_LIB standard
J 0
(-6775 4575);
DISPLAY INVISIBLE (-6775 4575);
FORCEPROP 1 LAST BODY_TYPE PLUMBING
J 0
(-6775 4625);
DISPLAY 0.872340 (-6775 4625);
PAINT GREEN (-6775 4625);
DISPLAY INVISIBLE (-6775 4625);
FORCEPROP 1 LAST HDL_TAP TRUE
J 0
(-6450 4450);
DISPLAY 0.872340 (-6450 4450);
DISPLAY INVISIBLE (-6450 4450);
FORCEPROP 1 LAST PATH I65
J 0
(-6777 4575);
DISPLAY 0.872340 (-6777 4575);
PAINT GREEN (-6777 4575);
DISPLAY INVISIBLE (-6777 4575);
FORCEADD TAP..1
(-6775 4925);
FORCEPROP 3 LASTPIN (-6825 4925) SIG_NAME P5E_CPU1_P0_TX_BUF_DN<13>
J 0
(-6815 4935);
DISPLAY 0.659574 (-6815 4935);
PAINT MONO (-6815 4935);
DISPLAY INVISIBLE (-6815 4935);
FORCEPROP 1 LASTPIN (-6825 4925) BN 13
J 0
(-6837 4933);
DISPLAY 0.680851 (-6837 4933);
PAINT GREEN (-6837 4933);
FORCEPROP 2 LAST CDS_LIB standard
J 0
(-6775 4925);
DISPLAY INVISIBLE (-6775 4925);
FORCEPROP 1 LAST BODY_TYPE PLUMBING
J 0
(-6775 4975);
DISPLAY 0.872340 (-6775 4975);
PAINT GREEN (-6775 4975);
DISPLAY INVISIBLE (-6775 4975);
FORCEPROP 1 LAST HDL_TAP TRUE
J 0
(-6450 4800);
DISPLAY 0.872340 (-6450 4800);
DISPLAY INVISIBLE (-6450 4800);
FORCEPROP 1 LAST PATH I66
J 0
(-6777 4925);
DISPLAY 0.872340 (-6777 4925);
PAINT GREEN (-6777 4925);
DISPLAY INVISIBLE (-6777 4925);
FORCEADD TAP..1
(-6975 5025);
FORCEPROP 3 LASTPIN (-7025 5025) SIG_NAME P5E_CPU1_P0_TX_BUF_DP<13>
J 0
(-7015 5035);
DISPLAY 0.659574 (-7015 5035);
PAINT MONO (-7015 5035);
DISPLAY INVISIBLE (-7015 5035);
FORCEPROP 1 LASTPIN (-7025 5025) BN 13
J 0
(-7037 5033);
DISPLAY 0.680851 (-7037 5033);
PAINT GREEN (-7037 5033);
FORCEPROP 2 LAST CDS_LIB standard
J 0
(-6975 5025);
DISPLAY INVISIBLE (-6975 5025);
FORCEPROP 1 LAST BODY_TYPE PLUMBING
J 0
(-6975 5075);
DISPLAY 0.872340 (-6975 5075);
PAINT GREEN (-6975 5075);
DISPLAY INVISIBLE (-6975 5075);
FORCEPROP 1 LAST HDL_TAP TRUE
J 0
(-6650 4900);
DISPLAY 0.872340 (-6650 4900);
DISPLAY INVISIBLE (-6650 4900);
FORCEPROP 1 LAST PATH I67
J 0
(-6977 5025);
DISPLAY 0.872340 (-6977 5025);
PAINT GREEN (-6977 5025);
DISPLAY INVISIBLE (-6977 5025);
FORCEADD TAP..1
(-6775 5275);
FORCEPROP 3 LASTPIN (-6825 5275) SIG_NAME P5E_CPU1_P0_TX_BUF_DN<14>
J 0
(-6815 5285);
DISPLAY 0.659574 (-6815 5285);
PAINT MONO (-6815 5285);
DISPLAY INVISIBLE (-6815 5285);
FORCEPROP 1 LASTPIN (-6825 5275) BN 14
J 0
(-6837 5283);
DISPLAY 0.680851 (-6837 5283);
PAINT GREEN (-6837 5283);
FORCEPROP 2 LAST CDS_LIB standard
J 0
(-6775 5275);
DISPLAY INVISIBLE (-6775 5275);
FORCEPROP 1 LAST BODY_TYPE PLUMBING
J 0
(-6775 5325);
DISPLAY 0.872340 (-6775 5325);
PAINT GREEN (-6775 5325);
DISPLAY INVISIBLE (-6775 5325);
FORCEPROP 1 LAST HDL_TAP TRUE
J 0
(-6450 5150);
DISPLAY 0.872340 (-6450 5150);
DISPLAY INVISIBLE (-6450 5150);
FORCEPROP 1 LAST PATH I68
J 0
(-6777 5275);
DISPLAY 0.872340 (-6777 5275);
PAINT GREEN (-6777 5275);
DISPLAY INVISIBLE (-6777 5275);
FORCEADD TAP..1
(-6975 5375);
FORCEPROP 3 LASTPIN (-7025 5375) SIG_NAME P5E_CPU1_P0_TX_BUF_DP<14>
J 0
(-7015 5385);
DISPLAY 0.659574 (-7015 5385);
PAINT MONO (-7015 5385);
DISPLAY INVISIBLE (-7015 5385);
FORCEPROP 1 LASTPIN (-7025 5375) BN 14
J 0
(-7037 5383);
DISPLAY 0.680851 (-7037 5383);
PAINT GREEN (-7037 5383);
FORCEPROP 2 LAST CDS_LIB standard
J 0
(-6975 5375);
DISPLAY INVISIBLE (-6975 5375);
FORCEPROP 1 LAST BODY_TYPE PLUMBING
J 0
(-6975 5425);
DISPLAY 0.872340 (-6975 5425);
PAINT GREEN (-6975 5425);
DISPLAY INVISIBLE (-6975 5425);
FORCEPROP 1 LAST HDL_TAP TRUE
J 0
(-6650 5250);
DISPLAY 0.872340 (-6650 5250);
DISPLAY INVISIBLE (-6650 5250);
FORCEPROP 1 LAST PATH I69
J 0
(-6977 5375);
DISPLAY 0.872340 (-6977 5375);
PAINT GREEN (-6977 5375);
DISPLAY INVISIBLE (-6977 5375);
FORCEADD TAP..1
R 2
(-3325 1375);
FORCEPROP 3 LASTPIN (-3275 1375) SIG_NAME P5E_CPU1_P0_TX_BUF_DN<3>
J 0
(-3265 1385);
DISPLAY 0.659574 (-3265 1385);
PAINT MONO (-3265 1385);
DISPLAY INVISIBLE (-3265 1385);
FORCEPROP 1 LASTPIN (-3275 1375) BN 3
J 2
(-3263 1383);
DISPLAY 0.680851 (-3263 1383);
PAINT GREEN (-3263 1383);
FORCEPROP 2 LAST CDS_LIB standard
J 0
(-3325 1375);
DISPLAY INVISIBLE (-3325 1375);
FORCEPROP 1 LAST BODY_TYPE PLUMBING
J 2
(-3325 1425);
DISPLAY 0.872340 (-3325 1425);
PAINT GREEN (-3325 1425);
DISPLAY INVISIBLE (-3325 1425);
FORCEPROP 1 LAST HDL_TAP TRUE
J 2
(-3650 1250);
DISPLAY 0.872340 (-3650 1250);
DISPLAY INVISIBLE (-3650 1250);
FORCEPROP 1 LAST PATH I7
J 2
(-3323 1375);
DISPLAY 0.872340 (-3323 1375);
PAINT GREEN (-3323 1375);
DISPLAY INVISIBLE (-3323 1375);
FORCEADD TAP..1
(-6775 5625);
FORCEPROP 3 LASTPIN (-6825 5625) SIG_NAME P5E_CPU1_P0_TX_BUF_DN<15>
J 0
(-6815 5635);
DISPLAY 0.659574 (-6815 5635);
PAINT MONO (-6815 5635);
DISPLAY INVISIBLE (-6815 5635);
FORCEPROP 1 LASTPIN (-6825 5625) BN 15
J 0
(-6837 5633);
DISPLAY 0.680851 (-6837 5633);
PAINT GREEN (-6837 5633);
FORCEPROP 2 LAST CDS_LIB standard
J 0
(-6775 5625);
DISPLAY INVISIBLE (-6775 5625);
FORCEPROP 1 LAST BODY_TYPE PLUMBING
J 0
(-6775 5675);
DISPLAY 0.872340 (-6775 5675);
PAINT GREEN (-6775 5675);
DISPLAY INVISIBLE (-6775 5675);
FORCEPROP 1 LAST HDL_TAP TRUE
J 0
(-6450 5500);
DISPLAY 0.872340 (-6450 5500);
DISPLAY INVISIBLE (-6450 5500);
FORCEPROP 1 LAST PATH I70
J 0
(-6777 5625);
DISPLAY 0.872340 (-6777 5625);
PAINT GREEN (-6777 5625);
DISPLAY INVISIBLE (-6777 5625);
FORCEADD TAP..1
(-6975 5725);
FORCEPROP 3 LASTPIN (-7025 5725) SIG_NAME P5E_CPU1_P0_TX_BUF_DP<15>
J 0
(-7015 5735);
DISPLAY 0.659574 (-7015 5735);
PAINT MONO (-7015 5735);
DISPLAY INVISIBLE (-7015 5735);
FORCEPROP 1 LASTPIN (-7025 5725) BN 15
J 0
(-7037 5733);
DISPLAY 0.680851 (-7037 5733);
PAINT GREEN (-7037 5733);
FORCEPROP 2 LAST CDS_LIB standard
J 0
(-6975 5725);
DISPLAY INVISIBLE (-6975 5725);
FORCEPROP 1 LAST BODY_TYPE PLUMBING
J 0
(-6975 5775);
DISPLAY 0.872340 (-6975 5775);
PAINT GREEN (-6975 5775);
DISPLAY INVISIBLE (-6975 5775);
FORCEPROP 1 LAST HDL_TAP TRUE
J 0
(-6650 5600);
DISPLAY 0.872340 (-6650 5600);
DISPLAY INVISIBLE (-6650 5600);
FORCEPROP 1 LAST PATH I71
J 0
(-6977 5725);
DISPLAY 0.872340 (-6977 5725);
PAINT GREEN (-6977 5725);
DISPLAY INVISIBLE (-6977 5725);
FORCEADD OFFPAGE..5
R 2
(-5800 5650);
FORCEPROP 2 LAST $XR0 320 
J 0
(-5611 5650);
DISPLAY 0.638298 (-5611 5650);
PAINT MONO (-5611 5650);
FORCEPROP 2 LAST CDS_LIB standard
J 0
(-5800 5650);
DISPLAY INVISIBLE (-5800 5650);
FORCEPROP 1 LAST OFFPAGE TRUE
J 2
(-6125 5525);
DISPLAY 0.872340 (-6125 5525);
PAINT GREEN (-6125 5525);
DISPLAY INVISIBLE (-6125 5525);
FORCEPROP 1 LAST COMMENT_BODY TRUE
J 2
(-5900 5575);
DISPLAY 0.872340 (-5900 5575);
PAINT GREEN (-5900 5575);
DISPLAY INVISIBLE (-5900 5575);
FORCEPROP 2 LAST PATH I72
J 0
(-5625 5725);
DISPLAY 0.680851 (-5625 5725);
DISPLAY INVISIBLE (-5625 5725);
FORCEADD OFFPAGE..5
R 2
(-5775 5750);
FORCEPROP 2 LAST $XR0 320 
J 0
(-5586 5750);
DISPLAY 0.638298 (-5586 5750);
PAINT MONO (-5586 5750);
FORCEPROP 2 LAST CDS_LIB standard
J 0
(-5775 5750);
DISPLAY INVISIBLE (-5775 5750);
FORCEPROP 1 LAST OFFPAGE TRUE
J 2
(-6100 5625);
DISPLAY 0.872340 (-6100 5625);
PAINT GREEN (-6100 5625);
DISPLAY INVISIBLE (-6100 5625);
FORCEPROP 1 LAST COMMENT_BODY TRUE
J 2
(-5875 5675);
DISPLAY 0.872340 (-5875 5675);
PAINT GREEN (-5875 5675);
DISPLAY INVISIBLE (-5875 5675);
FORCEPROP 2 LAST PATH I73
J 0
(-5600 5825);
DISPLAY 0.680851 (-5600 5825);
DISPLAY INVISIBLE (-5600 5825);
FORCEADD TAP..1
R 2
(-7925 600);
FORCEPROP 3 LASTPIN (-7875 600) SIG_NAME P5E_CPU1_P0_TX_BUF_DN<15>
J 0
(-7865 610);
DISPLAY 0.659574 (-7865 610);
PAINT MONO (-7865 610);
DISPLAY INVISIBLE (-7865 610);
FORCEPROP 1 LASTPIN (-7875 600) BN 15
J 2
(-7863 608);
DISPLAY 0.680851 (-7863 608);
PAINT GREEN (-7863 608);
FORCEPROP 2 LAST CDS_LIB standard
J 0
(-7925 600);
DISPLAY INVISIBLE (-7925 600);
FORCEPROP 1 LAST BODY_TYPE PLUMBING
J 2
(-7925 650);
DISPLAY 0.872340 (-7925 650);
PAINT GREEN (-7925 650);
DISPLAY INVISIBLE (-7925 650);
FORCEPROP 1 LAST HDL_TAP TRUE
J 2
(-8250 475);
DISPLAY 0.872340 (-8250 475);
DISPLAY INVISIBLE (-8250 475);
FORCEPROP 1 LAST PATH I74
J 2
(-7923 600);
DISPLAY 0.872340 (-7923 600);
PAINT GREEN (-7923 600);
DISPLAY INVISIBLE (-7923 600);
FORCEADD TAP..1
R 2
(-7675 650);
FORCEPROP 3 LASTPIN (-7625 650) SIG_NAME P5E_CPU1_P0_TX_BUF_DP<15>
J 0
(-7615 660);
DISPLAY 0.659574 (-7615 660);
PAINT MONO (-7615 660);
DISPLAY INVISIBLE (-7615 660);
FORCEPROP 1 LASTPIN (-7625 650) BN 15
J 2
(-7613 658);
DISPLAY 0.680851 (-7613 658);
PAINT GREEN (-7613 658);
FORCEPROP 2 LAST CDS_LIB standard
J 0
(-7675 650);
DISPLAY INVISIBLE (-7675 650);
FORCEPROP 1 LAST BODY_TYPE PLUMBING
J 2
(-7675 700);
DISPLAY 0.872340 (-7675 700);
PAINT GREEN (-7675 700);
DISPLAY INVISIBLE (-7675 700);
FORCEPROP 1 LAST HDL_TAP TRUE
J 2
(-8000 525);
DISPLAY 0.872340 (-8000 525);
DISPLAY INVISIBLE (-8000 525);
FORCEPROP 1 LAST PATH I75
J 2
(-7673 650);
DISPLAY 0.872340 (-7673 650);
PAINT GREEN (-7673 650);
DISPLAY INVISIBLE (-7673 650);
FORCEADD TAP..1
R 2
(-7925 800);
FORCEPROP 3 LASTPIN (-7875 800) SIG_NAME P5E_CPU1_P0_TX_BUF_DN<14>
J 0
(-7865 810);
DISPLAY 0.659574 (-7865 810);
PAINT MONO (-7865 810);
DISPLAY INVISIBLE (-7865 810);
FORCEPROP 1 LASTPIN (-7875 800) BN 14
J 2
(-7863 808);
DISPLAY 0.680851 (-7863 808);
PAINT GREEN (-7863 808);
FORCEPROP 2 LAST CDS_LIB standard
J 0
(-7925 800);
DISPLAY INVISIBLE (-7925 800);
FORCEPROP 1 LAST BODY_TYPE PLUMBING
J 2
(-7925 850);
DISPLAY 0.872340 (-7925 850);
PAINT GREEN (-7925 850);
DISPLAY INVISIBLE (-7925 850);
FORCEPROP 1 LAST HDL_TAP TRUE
J 2
(-8250 675);
DISPLAY 0.872340 (-8250 675);
DISPLAY INVISIBLE (-8250 675);
FORCEPROP 1 LAST PATH I76
J 2
(-7923 800);
DISPLAY 0.872340 (-7923 800);
PAINT GREEN (-7923 800);
DISPLAY INVISIBLE (-7923 800);
FORCEADD TAP..1
R 2
(-7925 1000);
FORCEPROP 3 LASTPIN (-7875 1000) SIG_NAME P5E_CPU1_P0_TX_BUF_DN<13>
J 0
(-7865 1010);
DISPLAY 0.659574 (-7865 1010);
PAINT MONO (-7865 1010);
DISPLAY INVISIBLE (-7865 1010);
FORCEPROP 1 LASTPIN (-7875 1000) BN 13
J 2
(-7863 1008);
DISPLAY 0.680851 (-7863 1008);
PAINT GREEN (-7863 1008);
FORCEPROP 2 LAST CDS_LIB standard
J 0
(-7925 1000);
DISPLAY INVISIBLE (-7925 1000);
FORCEPROP 1 LAST BODY_TYPE PLUMBING
J 2
(-7925 1050);
DISPLAY 0.872340 (-7925 1050);
PAINT GREEN (-7925 1050);
DISPLAY INVISIBLE (-7925 1050);
FORCEPROP 1 LAST HDL_TAP TRUE
J 2
(-8250 875);
DISPLAY 0.872340 (-8250 875);
DISPLAY INVISIBLE (-8250 875);
FORCEPROP 1 LAST PATH I77
J 2
(-7923 1000);
DISPLAY 0.872340 (-7923 1000);
PAINT GREEN (-7923 1000);
DISPLAY INVISIBLE (-7923 1000);
FORCEADD TAP..1
R 2
(-7925 1200);
FORCEPROP 3 LASTPIN (-7875 1200) SIG_NAME P5E_CPU1_P0_TX_BUF_DN<12>
J 0
(-7865 1210);
DISPLAY 0.659574 (-7865 1210);
PAINT MONO (-7865 1210);
DISPLAY INVISIBLE (-7865 1210);
FORCEPROP 1 LASTPIN (-7875 1200) BN 12
J 2
(-7863 1208);
DISPLAY 0.680851 (-7863 1208);
PAINT GREEN (-7863 1208);
FORCEPROP 2 LAST CDS_LIB standard
J 0
(-7925 1200);
DISPLAY INVISIBLE (-7925 1200);
FORCEPROP 1 LAST BODY_TYPE PLUMBING
J 2
(-7925 1250);
DISPLAY 0.872340 (-7925 1250);
PAINT GREEN (-7925 1250);
DISPLAY INVISIBLE (-7925 1250);
FORCEPROP 1 LAST HDL_TAP TRUE
J 2
(-8250 1075);
DISPLAY 0.872340 (-8250 1075);
DISPLAY INVISIBLE (-8250 1075);
FORCEPROP 1 LAST PATH I78
J 2
(-7923 1200);
DISPLAY 0.872340 (-7923 1200);
PAINT GREEN (-7923 1200);
DISPLAY INVISIBLE (-7923 1200);
FORCEADD TAP..1
R 2
(-7675 850);
FORCEPROP 3 LASTPIN (-7625 850) SIG_NAME P5E_CPU1_P0_TX_BUF_DP<14>
J 0
(-7615 860);
DISPLAY 0.659574 (-7615 860);
PAINT MONO (-7615 860);
DISPLAY INVISIBLE (-7615 860);
FORCEPROP 1 LASTPIN (-7625 850) BN 14
J 2
(-7613 858);
DISPLAY 0.680851 (-7613 858);
PAINT GREEN (-7613 858);
FORCEPROP 2 LAST CDS_LIB standard
J 0
(-7675 850);
DISPLAY INVISIBLE (-7675 850);
FORCEPROP 1 LAST BODY_TYPE PLUMBING
J 2
(-7675 900);
DISPLAY 0.872340 (-7675 900);
PAINT GREEN (-7675 900);
DISPLAY INVISIBLE (-7675 900);
FORCEPROP 1 LAST HDL_TAP TRUE
J 2
(-8000 725);
DISPLAY 0.872340 (-8000 725);
DISPLAY INVISIBLE (-8000 725);
FORCEPROP 1 LAST PATH I79
J 2
(-7673 850);
DISPLAY 0.872340 (-7673 850);
PAINT GREEN (-7673 850);
DISPLAY INVISIBLE (-7673 850);
FORCEADD TAP..1
R 2
(-3325 1575);
FORCEPROP 3 LASTPIN (-3275 1575) SIG_NAME P5E_CPU1_P0_TX_BUF_DN<2>
J 0
(-3265 1585);
DISPLAY 0.659574 (-3265 1585);
PAINT MONO (-3265 1585);
DISPLAY INVISIBLE (-3265 1585);
FORCEPROP 1 LASTPIN (-3275 1575) BN 2
J 2
(-3263 1583);
DISPLAY 0.680851 (-3263 1583);
PAINT GREEN (-3263 1583);
FORCEPROP 2 LAST CDS_LIB standard
J 0
(-3325 1575);
DISPLAY INVISIBLE (-3325 1575);
FORCEPROP 1 LAST BODY_TYPE PLUMBING
J 2
(-3325 1625);
DISPLAY 0.872340 (-3325 1625);
PAINT GREEN (-3325 1625);
DISPLAY INVISIBLE (-3325 1625);
FORCEPROP 1 LAST HDL_TAP TRUE
J 2
(-3650 1450);
DISPLAY 0.872340 (-3650 1450);
DISPLAY INVISIBLE (-3650 1450);
FORCEPROP 1 LAST PATH I8
J 2
(-3323 1575);
DISPLAY 0.872340 (-3323 1575);
PAINT GREEN (-3323 1575);
DISPLAY INVISIBLE (-3323 1575);
FORCEADD TAP..1
R 2
(-7675 1050);
FORCEPROP 3 LASTPIN (-7625 1050) SIG_NAME P5E_CPU1_P0_TX_BUF_DP<13>
J 0
(-7615 1060);
DISPLAY 0.659574 (-7615 1060);
PAINT MONO (-7615 1060);
DISPLAY INVISIBLE (-7615 1060);
FORCEPROP 1 LASTPIN (-7625 1050) BN 13
J 2
(-7613 1058);
DISPLAY 0.680851 (-7613 1058);
PAINT GREEN (-7613 1058);
FORCEPROP 2 LAST CDS_LIB standard
J 0
(-7675 1050);
DISPLAY INVISIBLE (-7675 1050);
FORCEPROP 1 LAST BODY_TYPE PLUMBING
J 2
(-7675 1100);
DISPLAY 0.872340 (-7675 1100);
PAINT GREEN (-7675 1100);
DISPLAY INVISIBLE (-7675 1100);
FORCEPROP 1 LAST HDL_TAP TRUE
J 2
(-8000 925);
DISPLAY 0.872340 (-8000 925);
DISPLAY INVISIBLE (-8000 925);
FORCEPROP 1 LAST PATH I80
J 2
(-7673 1050);
DISPLAY 0.872340 (-7673 1050);
PAINT GREEN (-7673 1050);
DISPLAY INVISIBLE (-7673 1050);
FORCEADD TAP..1
R 2
(-7925 1400);
FORCEPROP 3 LASTPIN (-7875 1400) SIG_NAME P5E_CPU1_P0_TX_BUF_DN<11>
J 0
(-7865 1410);
DISPLAY 0.659574 (-7865 1410);
PAINT MONO (-7865 1410);
DISPLAY INVISIBLE (-7865 1410);
FORCEPROP 1 LASTPIN (-7875 1400) BN 11
J 2
(-7863 1408);
DISPLAY 0.680851 (-7863 1408);
PAINT GREEN (-7863 1408);
FORCEPROP 2 LAST CDS_LIB standard
J 0
(-7925 1400);
DISPLAY INVISIBLE (-7925 1400);
FORCEPROP 1 LAST BODY_TYPE PLUMBING
J 2
(-7925 1450);
DISPLAY 0.872340 (-7925 1450);
PAINT GREEN (-7925 1450);
DISPLAY INVISIBLE (-7925 1450);
FORCEPROP 1 LAST HDL_TAP TRUE
J 2
(-8250 1275);
DISPLAY 0.872340 (-8250 1275);
DISPLAY INVISIBLE (-8250 1275);
FORCEPROP 1 LAST PATH I81
J 2
(-7923 1400);
DISPLAY 0.872340 (-7923 1400);
PAINT GREEN (-7923 1400);
DISPLAY INVISIBLE (-7923 1400);
FORCEADD TAP..1
R 2
(-7925 1600);
FORCEPROP 3 LASTPIN (-7875 1600) SIG_NAME P5E_CPU1_P0_TX_BUF_DN<10>
J 0
(-7865 1610);
DISPLAY 0.659574 (-7865 1610);
PAINT MONO (-7865 1610);
DISPLAY INVISIBLE (-7865 1610);
FORCEPROP 1 LASTPIN (-7875 1600) BN 10
J 2
(-7863 1608);
DISPLAY 0.680851 (-7863 1608);
PAINT GREEN (-7863 1608);
FORCEPROP 2 LAST CDS_LIB standard
J 0
(-7925 1600);
DISPLAY INVISIBLE (-7925 1600);
FORCEPROP 1 LAST BODY_TYPE PLUMBING
J 2
(-7925 1650);
DISPLAY 0.872340 (-7925 1650);
PAINT GREEN (-7925 1650);
DISPLAY INVISIBLE (-7925 1650);
FORCEPROP 1 LAST HDL_TAP TRUE
J 2
(-8250 1475);
DISPLAY 0.872340 (-8250 1475);
DISPLAY INVISIBLE (-8250 1475);
FORCEPROP 1 LAST PATH I82
J 2
(-7923 1600);
DISPLAY 0.872340 (-7923 1600);
PAINT GREEN (-7923 1600);
DISPLAY INVISIBLE (-7923 1600);
FORCEADD TAP..1
R 2
(-7675 1450);
FORCEPROP 3 LASTPIN (-7625 1450) SIG_NAME P5E_CPU1_P0_TX_BUF_DP<11>
J 0
(-7615 1460);
DISPLAY 0.659574 (-7615 1460);
PAINT MONO (-7615 1460);
DISPLAY INVISIBLE (-7615 1460);
FORCEPROP 1 LASTPIN (-7625 1450) BN 11
J 2
(-7613 1458);
DISPLAY 0.680851 (-7613 1458);
PAINT GREEN (-7613 1458);
FORCEPROP 2 LAST CDS_LIB standard
J 0
(-7675 1450);
DISPLAY INVISIBLE (-7675 1450);
FORCEPROP 1 LAST BODY_TYPE PLUMBING
J 2
(-7675 1500);
DISPLAY 0.872340 (-7675 1500);
PAINT GREEN (-7675 1500);
DISPLAY INVISIBLE (-7675 1500);
FORCEPROP 1 LAST HDL_TAP TRUE
J 2
(-8000 1325);
DISPLAY 0.872340 (-8000 1325);
DISPLAY INVISIBLE (-8000 1325);
FORCEPROP 1 LAST PATH I83
J 2
(-7673 1450);
DISPLAY 0.872340 (-7673 1450);
PAINT GREEN (-7673 1450);
DISPLAY INVISIBLE (-7673 1450);
FORCEADD TAP..1
R 2
(-7675 1250);
FORCEPROP 3 LASTPIN (-7625 1250) SIG_NAME P5E_CPU1_P0_TX_BUF_DP<12>
J 0
(-7615 1260);
DISPLAY 0.659574 (-7615 1260);
PAINT MONO (-7615 1260);
DISPLAY INVISIBLE (-7615 1260);
FORCEPROP 1 LASTPIN (-7625 1250) BN 12
J 2
(-7613 1258);
DISPLAY 0.680851 (-7613 1258);
PAINT GREEN (-7613 1258);
FORCEPROP 2 LAST CDS_LIB standard
J 0
(-7675 1250);
DISPLAY INVISIBLE (-7675 1250);
FORCEPROP 1 LAST BODY_TYPE PLUMBING
J 2
(-7675 1300);
DISPLAY 0.872340 (-7675 1300);
PAINT GREEN (-7675 1300);
DISPLAY INVISIBLE (-7675 1300);
FORCEPROP 1 LAST HDL_TAP TRUE
J 2
(-8000 1125);
DISPLAY 0.872340 (-8000 1125);
DISPLAY INVISIBLE (-8000 1125);
FORCEPROP 1 LAST PATH I84
J 2
(-7673 1250);
DISPLAY 0.872340 (-7673 1250);
PAINT GREEN (-7673 1250);
DISPLAY INVISIBLE (-7673 1250);
FORCEADD TAP..1
R 2
(-7675 1650);
FORCEPROP 3 LASTPIN (-7625 1650) SIG_NAME P5E_CPU1_P0_TX_BUF_DP<10>
J 0
(-7615 1660);
DISPLAY 0.659574 (-7615 1660);
PAINT MONO (-7615 1660);
DISPLAY INVISIBLE (-7615 1660);
FORCEPROP 1 LASTPIN (-7625 1650) BN 10
J 2
(-7613 1658);
DISPLAY 0.680851 (-7613 1658);
PAINT GREEN (-7613 1658);
FORCEPROP 2 LAST CDS_LIB standard
J 0
(-7675 1650);
DISPLAY INVISIBLE (-7675 1650);
FORCEPROP 1 LAST BODY_TYPE PLUMBING
J 2
(-7675 1700);
DISPLAY 0.872340 (-7675 1700);
PAINT GREEN (-7675 1700);
DISPLAY INVISIBLE (-7675 1700);
FORCEPROP 1 LAST HDL_TAP TRUE
J 2
(-8000 1525);
DISPLAY 0.872340 (-8000 1525);
DISPLAY INVISIBLE (-8000 1525);
FORCEPROP 1 LAST PATH I85
J 2
(-7673 1650);
DISPLAY 0.872340 (-7673 1650);
PAINT GREEN (-7673 1650);
DISPLAY INVISIBLE (-7673 1650);
FORCEADD Q_CAP_DIFFBUS..2
R 2
(-6950 600);
FORCEPROP 1 LAST LOCATION C6660
J 2
(-6675 600);
DISPLAY 0.723404 (-6675 600);
PAINT GREEN (-6675 600);
FORCEPROP 2 LAST $SEC 1
J 2
(-6775 675);
DISPLAY 0.680851 (-6775 675);
PAINT MONO (-6775 675);
DISPLAY INVISIBLE (-6775 675);
FORCEPROP 2 LAST CDS_SEC 1
J 2
(-6775 675);
DISPLAY 0.680851 (-6775 675);
DISPLAY INVISIBLE (-6775 675);
FORCEPROP 2 LASTPIN (-6875 600) $PN 1
J 0
(-6865 610);
DISPLAY 0.808511 (-6865 610);
FORCEPROP 2 LASTPIN (-7025 600) $PN 2
J 2
(-7035 610);
DISPLAY 0.808511 (-7035 610);
FORCEPROP 2 LAST VALUE DIFF BUS_0.22UF
J 2
(-7100 600);
DISPLAY 0.553191 (-7100 600);
FORCEPROP 1 LAST CDS_LMAN_SYM_OUTLINE -25,50,25,-50
J 2
(-6950 600);
DISPLAY 0.468085 (-6950 600);
PAINT GREEN (-6950 600);
DISPLAY INVISIBLE (-6950 600);
FORCEPROP 2 LAST CDS_LIB pure_quanta
J 2
(-6950 600);
DISPLAY INVISIBLE (-6950 600);
FORCEPROP 1 LAST PIN_NAMES_ROTATE TRUE
J 2
(-6950 600);
DISPLAY 0.489362 (-6950 600);
PAINT GREEN (-6950 600);
DISPLAY INVISIBLE (-6950 600);
FORCEPROP 2 LAST VOLTAGE 6.3V
J 2
(-7300 650);
DISPLAY 0.553191 (-7300 650);
DISPLAY INVISIBLE (-7300 650);
FORCEPROP 1 LAST MATERIAL X6S
J 2
(-6941 679);
DISPLAY 0.574468 (-6941 679);
PAINT GREEN (-6941 679);
DISPLAY INVISIBLE (-6941 679);
FORCEPROP 2 LAST PACK_TYPE C0201
J 2
(-7125 650);
DISPLAY 0.553191 (-7125 650);
DISPLAY INVISIBLE (-7125 650);
FORCEPROP 2 LAST TOLERANCE 20%
J 2
(-7025 650);
DISPLAY 0.553191 (-7025 650);
DISPLAY INVISIBLE (-7025 650);
FORCEPROP 1 LAST PATH I86
J 2
(-6950 600);
DISPLAY 0.723404 (-6950 600);
DISPLAY INVISIBLE (-6950 600);
FORCEPROP 1 LAST PART_NUMBER SP_CH4221MEE01
J 2
(-7066 688);
DISPLAY 0.574468 (-7066 688);
PAINT GREEN (-7066 688);
DISPLAY INVISIBLE (-7066 688);
FORCEPROP 1 LAST LOCATION C6660
J 0
(-6700 675);
DISPLAY 1.021277 (-6700 675);
DISPLAY INVISIBLE (-6700 675);
FORCEADD Q_CAP_DIFFBUS..2
R 2
(-6950 650);
FORCEPROP 1 LAST LOCATION C6659
J 2
(-6675 650);
DISPLAY 0.723404 (-6675 650);
PAINT GREEN (-6675 650);
FORCEPROP 2 LAST $SEC 1
J 2
(-6775 725);
DISPLAY 0.680851 (-6775 725);
PAINT MONO (-6775 725);
DISPLAY INVISIBLE (-6775 725);
FORCEPROP 2 LAST CDS_SEC 1
J 2
(-6775 725);
DISPLAY 0.680851 (-6775 725);
DISPLAY INVISIBLE (-6775 725);
FORCEPROP 2 LASTPIN (-6875 650) $PN 1
J 0
(-6865 660);
DISPLAY 0.808511 (-6865 660);
FORCEPROP 2 LASTPIN (-7025 650) $PN 2
J 2
(-7035 660);
DISPLAY 0.808511 (-7035 660);
FORCEPROP 2 LAST VALUE DIFF BUS_0.22UF
J 2
(-7100 650);
DISPLAY 0.553191 (-7100 650);
FORCEPROP 1 LAST CDS_LMAN_SYM_OUTLINE -25,50,25,-50
J 2
(-6950 650);
DISPLAY 0.468085 (-6950 650);
PAINT GREEN (-6950 650);
DISPLAY INVISIBLE (-6950 650);
FORCEPROP 2 LAST CDS_LIB pure_quanta
J 2
(-6950 650);
DISPLAY INVISIBLE (-6950 650);
FORCEPROP 1 LAST PIN_NAMES_ROTATE TRUE
J 2
(-6950 650);
DISPLAY 0.489362 (-6950 650);
PAINT GREEN (-6950 650);
DISPLAY INVISIBLE (-6950 650);
FORCEPROP 2 LAST VOLTAGE 6.3V
J 2
(-7300 700);
DISPLAY 0.553191 (-7300 700);
DISPLAY INVISIBLE (-7300 700);
FORCEPROP 1 LAST MATERIAL X6S
J 2
(-6941 729);
DISPLAY 0.574468 (-6941 729);
PAINT GREEN (-6941 729);
DISPLAY INVISIBLE (-6941 729);
FORCEPROP 2 LAST PACK_TYPE C0201
J 2
(-7125 700);
DISPLAY 0.553191 (-7125 700);
DISPLAY INVISIBLE (-7125 700);
FORCEPROP 2 LAST TOLERANCE 20%
J 2
(-7025 700);
DISPLAY 0.553191 (-7025 700);
DISPLAY INVISIBLE (-7025 700);
FORCEPROP 1 LAST PATH I87
J 2
(-6950 650);
DISPLAY 0.723404 (-6950 650);
DISPLAY INVISIBLE (-6950 650);
FORCEPROP 1 LAST PART_NUMBER SP_CH4221MEE01
J 2
(-7066 738);
DISPLAY 0.574468 (-7066 738);
PAINT GREEN (-7066 738);
DISPLAY INVISIBLE (-7066 738);
FORCEPROP 1 LAST LOCATION C6659
J 0
(-6700 725);
DISPLAY 1.021277 (-6700 725);
DISPLAY INVISIBLE (-6700 725);
FORCEADD Q_CAP_DIFFBUS..2
R 2
(-6950 800);
FORCEPROP 1 LAST LOCATION C6658
J 2
(-6675 800);
DISPLAY 0.723404 (-6675 800);
PAINT GREEN (-6675 800);
FORCEPROP 2 LAST $SEC 1
J 2
(-6775 875);
DISPLAY 0.680851 (-6775 875);
PAINT MONO (-6775 875);
DISPLAY INVISIBLE (-6775 875);
FORCEPROP 2 LAST CDS_SEC 1
J 2
(-6775 875);
DISPLAY 0.680851 (-6775 875);
DISPLAY INVISIBLE (-6775 875);
FORCEPROP 2 LASTPIN (-6875 800) $PN 1
J 0
(-6865 810);
DISPLAY 0.808511 (-6865 810);
FORCEPROP 2 LASTPIN (-7025 800) $PN 2
J 2
(-7035 810);
DISPLAY 0.808511 (-7035 810);
FORCEPROP 2 LAST VALUE DIFF BUS_0.22UF
J 2
(-7100 800);
DISPLAY 0.553191 (-7100 800);
FORCEPROP 1 LAST CDS_LMAN_SYM_OUTLINE -25,50,25,-50
J 2
(-6950 800);
DISPLAY 0.468085 (-6950 800);
PAINT GREEN (-6950 800);
DISPLAY INVISIBLE (-6950 800);
FORCEPROP 2 LAST CDS_LIB pure_quanta
J 2
(-6950 800);
DISPLAY INVISIBLE (-6950 800);
FORCEPROP 1 LAST PIN_NAMES_ROTATE TRUE
J 2
(-6950 800);
DISPLAY 0.489362 (-6950 800);
PAINT GREEN (-6950 800);
DISPLAY INVISIBLE (-6950 800);
FORCEPROP 2 LAST VOLTAGE 6.3V
J 2
(-7300 850);
DISPLAY 0.553191 (-7300 850);
DISPLAY INVISIBLE (-7300 850);
FORCEPROP 1 LAST MATERIAL X6S
J 2
(-6941 879);
DISPLAY 0.574468 (-6941 879);
PAINT GREEN (-6941 879);
DISPLAY INVISIBLE (-6941 879);
FORCEPROP 2 LAST PACK_TYPE C0201
J 2
(-7125 850);
DISPLAY 0.553191 (-7125 850);
DISPLAY INVISIBLE (-7125 850);
FORCEPROP 2 LAST TOLERANCE 20%
J 2
(-7025 850);
DISPLAY 0.553191 (-7025 850);
DISPLAY INVISIBLE (-7025 850);
FORCEPROP 1 LAST PATH I88
J 2
(-6950 800);
DISPLAY 0.723404 (-6950 800);
DISPLAY INVISIBLE (-6950 800);
FORCEPROP 1 LAST PART_NUMBER SP_CH4221MEE01
J 2
(-7066 888);
DISPLAY 0.574468 (-7066 888);
PAINT GREEN (-7066 888);
DISPLAY INVISIBLE (-7066 888);
FORCEPROP 1 LAST LOCATION C6658
J 0
(-6700 875);
DISPLAY 1.021277 (-6700 875);
DISPLAY INVISIBLE (-6700 875);
FORCEADD Q_CAP_DIFFBUS..2
R 2
(-6950 850);
FORCEPROP 1 LAST LOCATION C6657
J 2
(-6675 850);
DISPLAY 0.723404 (-6675 850);
PAINT GREEN (-6675 850);
FORCEPROP 2 LAST $SEC 1
J 2
(-6775 925);
DISPLAY 0.680851 (-6775 925);
PAINT MONO (-6775 925);
DISPLAY INVISIBLE (-6775 925);
FORCEPROP 2 LAST CDS_SEC 1
J 2
(-6775 925);
DISPLAY 0.680851 (-6775 925);
DISPLAY INVISIBLE (-6775 925);
FORCEPROP 2 LASTPIN (-6875 850) $PN 1
J 0
(-6865 860);
DISPLAY 0.808511 (-6865 860);
FORCEPROP 2 LASTPIN (-7025 850) $PN 2
J 2
(-7035 860);
DISPLAY 0.808511 (-7035 860);
FORCEPROP 2 LAST VALUE DIFF BUS_0.22UF
J 2
(-7100 850);
DISPLAY 0.553191 (-7100 850);
FORCEPROP 2 LAST CDS_LIB pure_quanta
J 2
(-6950 850);
DISPLAY INVISIBLE (-6950 850);
FORCEPROP 1 LAST CDS_LMAN_SYM_OUTLINE -25,50,25,-50
J 2
(-6950 850);
DISPLAY 0.468085 (-6950 850);
PAINT GREEN (-6950 850);
DISPLAY INVISIBLE (-6950 850);
FORCEPROP 1 LAST PIN_NAMES_ROTATE TRUE
J 2
(-6950 850);
DISPLAY 0.489362 (-6950 850);
PAINT GREEN (-6950 850);
DISPLAY INVISIBLE (-6950 850);
FORCEPROP 2 LAST VOLTAGE 6.3V
J 2
(-7300 900);
DISPLAY 0.553191 (-7300 900);
DISPLAY INVISIBLE (-7300 900);
FORCEPROP 1 LAST MATERIAL X6S
J 2
(-6941 929);
DISPLAY 0.574468 (-6941 929);
PAINT GREEN (-6941 929);
DISPLAY INVISIBLE (-6941 929);
FORCEPROP 2 LAST PACK_TYPE C0201
J 2
(-7125 900);
DISPLAY 0.553191 (-7125 900);
DISPLAY INVISIBLE (-7125 900);
FORCEPROP 2 LAST TOLERANCE 20%
J 2
(-7025 900);
DISPLAY 0.553191 (-7025 900);
DISPLAY INVISIBLE (-7025 900);
FORCEPROP 1 LAST PATH I89
J 2
(-6950 850);
DISPLAY 0.723404 (-6950 850);
DISPLAY INVISIBLE (-6950 850);
FORCEPROP 1 LAST PART_NUMBER SP_CH4221MEE01
J 2
(-7066 938);
DISPLAY 0.574468 (-7066 938);
PAINT GREEN (-7066 938);
DISPLAY INVISIBLE (-7066 938);
FORCEPROP 1 LAST LOCATION C6657
J 0
(-6700 925);
DISPLAY 1.021277 (-6700 925);
DISPLAY INVISIBLE (-6700 925);
FORCEADD TAP..1
R 2
(-3075 625);
FORCEPROP 3 LASTPIN (-3025 625) SIG_NAME P5E_CPU1_P0_TX_BUF_DP<7>
J 0
(-3015 635);
DISPLAY 0.659574 (-3015 635);
PAINT MONO (-3015 635);
DISPLAY INVISIBLE (-3015 635);
FORCEPROP 1 LASTPIN (-3025 625) BN 7
J 2
(-3013 633);
DISPLAY 0.680851 (-3013 633);
PAINT GREEN (-3013 633);
FORCEPROP 2 LAST CDS_LIB standard
J 0
(-3075 625);
DISPLAY INVISIBLE (-3075 625);
FORCEPROP 1 LAST BODY_TYPE PLUMBING
J 2
(-3075 675);
DISPLAY 0.872340 (-3075 675);
PAINT GREEN (-3075 675);
DISPLAY INVISIBLE (-3075 675);
FORCEPROP 1 LAST HDL_TAP TRUE
J 2
(-3400 500);
DISPLAY 0.872340 (-3400 500);
DISPLAY INVISIBLE (-3400 500);
FORCEPROP 1 LAST PATH I9
J 2
(-3073 625);
DISPLAY 0.872340 (-3073 625);
PAINT GREEN (-3073 625);
DISPLAY INVISIBLE (-3073 625);
FORCEADD Q_CAP_DIFFBUS..2
R 2
(-6950 1000);
FORCEPROP 1 LAST LOCATION C6656
J 2
(-6675 1000);
DISPLAY 0.723404 (-6675 1000);
PAINT GREEN (-6675 1000);
FORCEPROP 2 LAST $SEC 1
J 2
(-6775 1075);
DISPLAY 0.680851 (-6775 1075);
PAINT MONO (-6775 1075);
DISPLAY INVISIBLE (-6775 1075);
FORCEPROP 2 LAST CDS_SEC 1
J 2
(-6775 1075);
DISPLAY 0.680851 (-6775 1075);
DISPLAY INVISIBLE (-6775 1075);
FORCEPROP 2 LASTPIN (-6875 1000) $PN 1
J 0
(-6865 1010);
DISPLAY 0.808511 (-6865 1010);
FORCEPROP 2 LASTPIN (-7025 1000) $PN 2
J 2
(-7035 1010);
DISPLAY 0.808511 (-7035 1010);
FORCEPROP 2 LAST VALUE DIFF BUS_0.22UF
J 2
(-7100 1000);
DISPLAY 0.553191 (-7100 1000);
FORCEPROP 1 LAST CDS_LMAN_SYM_OUTLINE -25,50,25,-50
J 2
(-6950 1000);
DISPLAY 0.468085 (-6950 1000);
PAINT GREEN (-6950 1000);
DISPLAY INVISIBLE (-6950 1000);
FORCEPROP 2 LAST CDS_LIB pure_quanta
J 2
(-6950 1000);
DISPLAY INVISIBLE (-6950 1000);
FORCEPROP 1 LAST PIN_NAMES_ROTATE TRUE
J 2
(-6950 1000);
DISPLAY 0.489362 (-6950 1000);
PAINT GREEN (-6950 1000);
DISPLAY INVISIBLE (-6950 1000);
FORCEPROP 2 LAST VOLTAGE 6.3V
J 2
(-7300 1050);
DISPLAY 0.553191 (-7300 1050);
DISPLAY INVISIBLE (-7300 1050);
FORCEPROP 1 LAST MATERIAL X6S
J 2
(-6941 1079);
DISPLAY 0.574468 (-6941 1079);
PAINT GREEN (-6941 1079);
DISPLAY INVISIBLE (-6941 1079);
FORCEPROP 2 LAST PACK_TYPE C0201
J 2
(-7125 1050);
DISPLAY 0.553191 (-7125 1050);
DISPLAY INVISIBLE (-7125 1050);
FORCEPROP 2 LAST TOLERANCE 20%
J 2
(-7025 1050);
DISPLAY 0.553191 (-7025 1050);
DISPLAY INVISIBLE (-7025 1050);
FORCEPROP 1 LAST PATH I90
J 2
(-6950 1000);
DISPLAY 0.723404 (-6950 1000);
DISPLAY INVISIBLE (-6950 1000);
FORCEPROP 1 LAST PART_NUMBER SP_CH4221MEE01
J 2
(-7066 1088);
DISPLAY 0.574468 (-7066 1088);
PAINT GREEN (-7066 1088);
DISPLAY INVISIBLE (-7066 1088);
FORCEPROP 1 LAST LOCATION C6656
J 0
(-6700 1075);
DISPLAY 1.021277 (-6700 1075);
DISPLAY INVISIBLE (-6700 1075);
FORCEADD Q_CAP_DIFFBUS..2
R 2
(-6950 1050);
FORCEPROP 1 LAST LOCATION C6655
J 2
(-6675 1050);
DISPLAY 0.723404 (-6675 1050);
PAINT GREEN (-6675 1050);
FORCEPROP 2 LAST $SEC 1
J 2
(-6775 1125);
DISPLAY 0.680851 (-6775 1125);
PAINT MONO (-6775 1125);
DISPLAY INVISIBLE (-6775 1125);
FORCEPROP 2 LAST CDS_SEC 1
J 2
(-6775 1125);
DISPLAY 0.680851 (-6775 1125);
DISPLAY INVISIBLE (-6775 1125);
FORCEPROP 2 LASTPIN (-6875 1050) $PN 1
J 0
(-6865 1060);
DISPLAY 0.808511 (-6865 1060);
FORCEPROP 2 LASTPIN (-7025 1050) $PN 2
J 2
(-7035 1060);
DISPLAY 0.808511 (-7035 1060);
FORCEPROP 2 LAST VALUE DIFF BUS_0.22UF
J 2
(-7100 1050);
DISPLAY 0.553191 (-7100 1050);
FORCEPROP 1 LAST CDS_LMAN_SYM_OUTLINE -25,50,25,-50
J 2
(-6950 1050);
DISPLAY 0.468085 (-6950 1050);
PAINT GREEN (-6950 1050);
DISPLAY INVISIBLE (-6950 1050);
FORCEPROP 2 LAST CDS_LIB pure_quanta
J 2
(-6950 1050);
DISPLAY INVISIBLE (-6950 1050);
FORCEPROP 1 LAST PIN_NAMES_ROTATE TRUE
J 2
(-6950 1050);
DISPLAY 0.489362 (-6950 1050);
PAINT GREEN (-6950 1050);
DISPLAY INVISIBLE (-6950 1050);
FORCEPROP 2 LAST VOLTAGE 6.3V
J 2
(-7300 1100);
DISPLAY 0.553191 (-7300 1100);
DISPLAY INVISIBLE (-7300 1100);
FORCEPROP 1 LAST MATERIAL X6S
J 2
(-6941 1129);
DISPLAY 0.574468 (-6941 1129);
PAINT GREEN (-6941 1129);
DISPLAY INVISIBLE (-6941 1129);
FORCEPROP 2 LAST PACK_TYPE C0201
J 2
(-7125 1100);
DISPLAY 0.553191 (-7125 1100);
DISPLAY INVISIBLE (-7125 1100);
FORCEPROP 2 LAST TOLERANCE 20%
J 2
(-7025 1100);
DISPLAY 0.553191 (-7025 1100);
DISPLAY INVISIBLE (-7025 1100);
FORCEPROP 1 LAST PATH I91
J 2
(-6950 1050);
DISPLAY 0.723404 (-6950 1050);
DISPLAY INVISIBLE (-6950 1050);
FORCEPROP 1 LAST PART_NUMBER SP_CH4221MEE01
J 2
(-7066 1138);
DISPLAY 0.574468 (-7066 1138);
PAINT GREEN (-7066 1138);
DISPLAY INVISIBLE (-7066 1138);
FORCEPROP 1 LAST LOCATION C6655
J 0
(-6700 1125);
DISPLAY 1.021277 (-6700 1125);
DISPLAY INVISIBLE (-6700 1125);
FORCEADD Q_CAP_DIFFBUS..2
R 2
(-6950 1200);
FORCEPROP 1 LAST LOCATION C6654
J 2
(-6675 1200);
DISPLAY 0.723404 (-6675 1200);
PAINT GREEN (-6675 1200);
FORCEPROP 2 LAST $SEC 1
J 2
(-6775 1275);
DISPLAY 0.680851 (-6775 1275);
PAINT MONO (-6775 1275);
DISPLAY INVISIBLE (-6775 1275);
FORCEPROP 2 LAST CDS_SEC 1
J 2
(-6775 1275);
DISPLAY 0.680851 (-6775 1275);
DISPLAY INVISIBLE (-6775 1275);
FORCEPROP 2 LASTPIN (-6875 1200) $PN 1
J 0
(-6865 1210);
DISPLAY 0.808511 (-6865 1210);
FORCEPROP 2 LASTPIN (-7025 1200) $PN 2
J 2
(-7035 1210);
DISPLAY 0.808511 (-7035 1210);
FORCEPROP 2 LAST VALUE DIFF BUS_0.22UF
J 2
(-7100 1200);
DISPLAY 0.553191 (-7100 1200);
FORCEPROP 2 LAST CDS_LIB pure_quanta
J 2
(-6950 1200);
DISPLAY INVISIBLE (-6950 1200);
FORCEPROP 1 LAST CDS_LMAN_SYM_OUTLINE -25,50,25,-50
J 2
(-6950 1200);
DISPLAY 0.468085 (-6950 1200);
PAINT GREEN (-6950 1200);
DISPLAY INVISIBLE (-6950 1200);
FORCEPROP 1 LAST PIN_NAMES_ROTATE TRUE
J 2
(-6950 1200);
DISPLAY 0.489362 (-6950 1200);
PAINT GREEN (-6950 1200);
DISPLAY INVISIBLE (-6950 1200);
FORCEPROP 2 LAST VOLTAGE 6.3V
J 2
(-7300 1250);
DISPLAY 0.553191 (-7300 1250);
DISPLAY INVISIBLE (-7300 1250);
FORCEPROP 1 LAST MATERIAL X6S
J 2
(-6941 1279);
DISPLAY 0.574468 (-6941 1279);
PAINT GREEN (-6941 1279);
DISPLAY INVISIBLE (-6941 1279);
FORCEPROP 2 LAST PACK_TYPE C0201
J 2
(-7125 1250);
DISPLAY 0.553191 (-7125 1250);
DISPLAY INVISIBLE (-7125 1250);
FORCEPROP 2 LAST TOLERANCE 20%
J 2
(-7025 1250);
DISPLAY 0.553191 (-7025 1250);
DISPLAY INVISIBLE (-7025 1250);
FORCEPROP 1 LAST PATH I92
J 2
(-6950 1200);
DISPLAY 0.723404 (-6950 1200);
DISPLAY INVISIBLE (-6950 1200);
FORCEPROP 1 LAST PART_NUMBER SP_CH4221MEE01
J 2
(-7066 1288);
DISPLAY 0.574468 (-7066 1288);
PAINT GREEN (-7066 1288);
DISPLAY INVISIBLE (-7066 1288);
FORCEPROP 1 LAST LOCATION C6654
J 0
(-6700 1275);
DISPLAY 1.021277 (-6700 1275);
DISPLAY INVISIBLE (-6700 1275);
FORCEADD Q_CAP_DIFFBUS..2
R 2
(-6950 1250);
FORCEPROP 1 LAST LOCATION C6653
J 2
(-6675 1250);
DISPLAY 0.723404 (-6675 1250);
PAINT GREEN (-6675 1250);
FORCEPROP 2 LAST $SEC 1
J 2
(-6775 1325);
DISPLAY 0.680851 (-6775 1325);
PAINT MONO (-6775 1325);
DISPLAY INVISIBLE (-6775 1325);
FORCEPROP 2 LAST CDS_SEC 1
J 2
(-6775 1325);
DISPLAY 0.680851 (-6775 1325);
DISPLAY INVISIBLE (-6775 1325);
FORCEPROP 2 LASTPIN (-6875 1250) $PN 1
J 0
(-6865 1260);
DISPLAY 0.808511 (-6865 1260);
FORCEPROP 2 LASTPIN (-7025 1250) $PN 2
J 2
(-7035 1260);
DISPLAY 0.808511 (-7035 1260);
FORCEPROP 2 LAST VALUE DIFF BUS_0.22UF
J 2
(-7100 1250);
DISPLAY 0.553191 (-7100 1250);
FORCEPROP 2 LAST CDS_LIB pure_quanta
J 2
(-6950 1250);
DISPLAY INVISIBLE (-6950 1250);
FORCEPROP 1 LAST CDS_LMAN_SYM_OUTLINE -25,50,25,-50
J 2
(-6950 1250);
DISPLAY 0.468085 (-6950 1250);
PAINT GREEN (-6950 1250);
DISPLAY INVISIBLE (-6950 1250);
FORCEPROP 1 LAST PIN_NAMES_ROTATE TRUE
J 2
(-6950 1250);
DISPLAY 0.489362 (-6950 1250);
PAINT GREEN (-6950 1250);
DISPLAY INVISIBLE (-6950 1250);
FORCEPROP 2 LAST VOLTAGE 6.3V
J 2
(-7300 1300);
DISPLAY 0.553191 (-7300 1300);
DISPLAY INVISIBLE (-7300 1300);
FORCEPROP 1 LAST MATERIAL X6S
J 2
(-6941 1329);
DISPLAY 0.574468 (-6941 1329);
PAINT GREEN (-6941 1329);
DISPLAY INVISIBLE (-6941 1329);
FORCEPROP 2 LAST PACK_TYPE C0201
J 2
(-7125 1300);
DISPLAY 0.553191 (-7125 1300);
DISPLAY INVISIBLE (-7125 1300);
FORCEPROP 2 LAST TOLERANCE 20%
J 2
(-7025 1300);
DISPLAY 0.553191 (-7025 1300);
DISPLAY INVISIBLE (-7025 1300);
FORCEPROP 1 LAST PATH I93
J 2
(-6950 1250);
DISPLAY 0.723404 (-6950 1250);
DISPLAY INVISIBLE (-6950 1250);
FORCEPROP 1 LAST PART_NUMBER SP_CH4221MEE01
J 2
(-7066 1338);
DISPLAY 0.574468 (-7066 1338);
PAINT GREEN (-7066 1338);
DISPLAY INVISIBLE (-7066 1338);
FORCEPROP 1 LAST LOCATION C6653
J 0
(-6700 1325);
DISPLAY 1.021277 (-6700 1325);
DISPLAY INVISIBLE (-6700 1325);
FORCEADD Q_CAP_DIFFBUS..2
R 2
(-6950 1400);
FORCEPROP 1 LAST LOCATION C6652
J 2
(-6675 1400);
DISPLAY 0.723404 (-6675 1400);
PAINT GREEN (-6675 1400);
FORCEPROP 2 LAST $SEC 1
J 2
(-6775 1475);
DISPLAY 0.680851 (-6775 1475);
PAINT MONO (-6775 1475);
DISPLAY INVISIBLE (-6775 1475);
FORCEPROP 2 LAST CDS_SEC 1
J 2
(-6775 1475);
DISPLAY 0.680851 (-6775 1475);
DISPLAY INVISIBLE (-6775 1475);
FORCEPROP 2 LASTPIN (-6875 1400) $PN 1
J 0
(-6865 1410);
DISPLAY 0.808511 (-6865 1410);
FORCEPROP 2 LASTPIN (-7025 1400) $PN 2
J 2
(-7035 1410);
DISPLAY 0.808511 (-7035 1410);
FORCEPROP 2 LAST VALUE DIFF BUS_0.22UF
J 2
(-7100 1400);
DISPLAY 0.553191 (-7100 1400);
FORCEPROP 1 LAST CDS_LMAN_SYM_OUTLINE -25,50,25,-50
J 2
(-6950 1400);
DISPLAY 0.468085 (-6950 1400);
PAINT GREEN (-6950 1400);
DISPLAY INVISIBLE (-6950 1400);
FORCEPROP 2 LAST CDS_LIB pure_quanta
J 2
(-6950 1400);
DISPLAY INVISIBLE (-6950 1400);
FORCEPROP 1 LAST PIN_NAMES_ROTATE TRUE
J 2
(-6950 1400);
DISPLAY 0.489362 (-6950 1400);
PAINT GREEN (-6950 1400);
DISPLAY INVISIBLE (-6950 1400);
FORCEPROP 2 LAST VOLTAGE 6.3V
J 2
(-7300 1450);
DISPLAY 0.553191 (-7300 1450);
DISPLAY INVISIBLE (-7300 1450);
FORCEPROP 1 LAST MATERIAL X6S
J 2
(-6941 1479);
DISPLAY 0.574468 (-6941 1479);
PAINT GREEN (-6941 1479);
DISPLAY INVISIBLE (-6941 1479);
FORCEPROP 2 LAST PACK_TYPE C0201
J 2
(-7125 1450);
DISPLAY 0.553191 (-7125 1450);
DISPLAY INVISIBLE (-7125 1450);
FORCEPROP 2 LAST TOLERANCE 20%
J 2
(-7025 1450);
DISPLAY 0.553191 (-7025 1450);
DISPLAY INVISIBLE (-7025 1450);
FORCEPROP 1 LAST PATH I94
J 2
(-6950 1400);
DISPLAY 0.723404 (-6950 1400);
DISPLAY INVISIBLE (-6950 1400);
FORCEPROP 1 LAST PART_NUMBER SP_CH4221MEE01
J 2
(-7066 1488);
DISPLAY 0.574468 (-7066 1488);
PAINT GREEN (-7066 1488);
DISPLAY INVISIBLE (-7066 1488);
FORCEPROP 1 LAST LOCATION C6652
J 0
(-6700 1475);
DISPLAY 1.021277 (-6700 1475);
DISPLAY INVISIBLE (-6700 1475);
FORCEADD Q_CAP_DIFFBUS..2
R 2
(-6950 1450);
FORCEPROP 1 LAST LOCATION C6651
J 2
(-6675 1450);
DISPLAY 0.723404 (-6675 1450);
PAINT GREEN (-6675 1450);
FORCEPROP 2 LAST $SEC 1
J 2
(-6775 1525);
DISPLAY 0.680851 (-6775 1525);
PAINT MONO (-6775 1525);
DISPLAY INVISIBLE (-6775 1525);
FORCEPROP 2 LAST CDS_SEC 1
J 2
(-6775 1525);
DISPLAY 0.680851 (-6775 1525);
DISPLAY INVISIBLE (-6775 1525);
FORCEPROP 2 LASTPIN (-6875 1450) $PN 1
J 0
(-6865 1460);
DISPLAY 0.808511 (-6865 1460);
FORCEPROP 2 LASTPIN (-7025 1450) $PN 2
J 2
(-7035 1460);
DISPLAY 0.808511 (-7035 1460);
FORCEPROP 2 LAST VALUE DIFF BUS_0.22UF
J 2
(-7100 1450);
DISPLAY 0.553191 (-7100 1450);
FORCEPROP 1 LAST CDS_LMAN_SYM_OUTLINE -25,50,25,-50
J 2
(-6950 1450);
DISPLAY 0.468085 (-6950 1450);
PAINT GREEN (-6950 1450);
DISPLAY INVISIBLE (-6950 1450);
FORCEPROP 2 LAST CDS_LIB pure_quanta
J 2
(-6950 1450);
DISPLAY INVISIBLE (-6950 1450);
FORCEPROP 1 LAST PIN_NAMES_ROTATE TRUE
J 2
(-6950 1450);
DISPLAY 0.489362 (-6950 1450);
PAINT GREEN (-6950 1450);
DISPLAY INVISIBLE (-6950 1450);
FORCEPROP 2 LAST VOLTAGE 6.3V
J 2
(-7300 1500);
DISPLAY 0.553191 (-7300 1500);
DISPLAY INVISIBLE (-7300 1500);
FORCEPROP 1 LAST MATERIAL X6S
J 2
(-6941 1529);
DISPLAY 0.574468 (-6941 1529);
PAINT GREEN (-6941 1529);
DISPLAY INVISIBLE (-6941 1529);
FORCEPROP 2 LAST PACK_TYPE C0201
J 2
(-7125 1500);
DISPLAY 0.553191 (-7125 1500);
DISPLAY INVISIBLE (-7125 1500);
FORCEPROP 2 LAST TOLERANCE 20%
J 2
(-7025 1500);
DISPLAY 0.553191 (-7025 1500);
DISPLAY INVISIBLE (-7025 1500);
FORCEPROP 1 LAST PATH I95
J 2
(-6950 1450);
DISPLAY 0.723404 (-6950 1450);
DISPLAY INVISIBLE (-6950 1450);
FORCEPROP 1 LAST PART_NUMBER SP_CH4221MEE01
J 2
(-7066 1538);
DISPLAY 0.574468 (-7066 1538);
PAINT GREEN (-7066 1538);
DISPLAY INVISIBLE (-7066 1538);
FORCEPROP 1 LAST LOCATION C6651
J 0
(-6700 1525);
DISPLAY 1.021277 (-6700 1525);
DISPLAY INVISIBLE (-6700 1525);
FORCEADD Q_CAP_DIFFBUS..2
R 2
(-6950 1650);
FORCEPROP 1 LAST LOCATION C6649
J 2
(-6675 1650);
DISPLAY 0.723404 (-6675 1650);
PAINT GREEN (-6675 1650);
FORCEPROP 2 LAST $SEC 1
J 2
(-6775 1725);
DISPLAY 0.680851 (-6775 1725);
PAINT MONO (-6775 1725);
DISPLAY INVISIBLE (-6775 1725);
FORCEPROP 2 LAST CDS_SEC 1
J 2
(-6775 1725);
DISPLAY 0.680851 (-6775 1725);
DISPLAY INVISIBLE (-6775 1725);
FORCEPROP 2 LASTPIN (-6875 1650) $PN 1
J 0
(-6865 1660);
DISPLAY 0.808511 (-6865 1660);
FORCEPROP 2 LASTPIN (-7025 1650) $PN 2
J 2
(-7035 1660);
DISPLAY 0.808511 (-7035 1660);
FORCEPROP 2 LAST VALUE DIFF BUS_0.22UF
J 2
(-7100 1650);
DISPLAY 0.553191 (-7100 1650);
FORCEPROP 1 LAST CDS_LMAN_SYM_OUTLINE -25,50,25,-50
J 2
(-6950 1650);
DISPLAY 0.468085 (-6950 1650);
PAINT GREEN (-6950 1650);
DISPLAY INVISIBLE (-6950 1650);
FORCEPROP 2 LAST CDS_LIB pure_quanta
J 2
(-6950 1650);
DISPLAY INVISIBLE (-6950 1650);
FORCEPROP 1 LAST PIN_NAMES_ROTATE TRUE
J 2
(-6950 1650);
DISPLAY 0.489362 (-6950 1650);
PAINT GREEN (-6950 1650);
DISPLAY INVISIBLE (-6950 1650);
FORCEPROP 2 LAST VOLTAGE 6.3V
J 2
(-7300 1700);
DISPLAY 0.553191 (-7300 1700);
DISPLAY INVISIBLE (-7300 1700);
FORCEPROP 1 LAST MATERIAL X6S
J 2
(-6941 1729);
DISPLAY 0.574468 (-6941 1729);
PAINT GREEN (-6941 1729);
DISPLAY INVISIBLE (-6941 1729);
FORCEPROP 2 LAST PACK_TYPE C0201
J 2
(-7125 1700);
DISPLAY 0.553191 (-7125 1700);
DISPLAY INVISIBLE (-7125 1700);
FORCEPROP 2 LAST TOLERANCE 20%
J 2
(-7025 1700);
DISPLAY 0.553191 (-7025 1700);
DISPLAY INVISIBLE (-7025 1700);
FORCEPROP 1 LAST PATH I96
J 2
(-6950 1650);
DISPLAY 0.723404 (-6950 1650);
DISPLAY INVISIBLE (-6950 1650);
FORCEPROP 1 LAST PART_NUMBER SP_CH4221MEE01
J 2
(-7066 1738);
DISPLAY 0.574468 (-7066 1738);
PAINT GREEN (-7066 1738);
DISPLAY INVISIBLE (-7066 1738);
FORCEPROP 1 LAST LOCATION C6649
J 0
(-6700 1725);
DISPLAY 1.021277 (-6700 1725);
DISPLAY INVISIBLE (-6700 1725);
FORCEADD Q_CAP_DIFFBUS..2
R 2
(-6950 1600);
FORCEPROP 1 LAST LOCATION C6650
J 2
(-6675 1600);
DISPLAY 0.723404 (-6675 1600);
PAINT GREEN (-6675 1600);
FORCEPROP 2 LAST $SEC 1
J 2
(-6775 1675);
DISPLAY 0.680851 (-6775 1675);
PAINT MONO (-6775 1675);
DISPLAY INVISIBLE (-6775 1675);
FORCEPROP 2 LAST CDS_SEC 1
J 2
(-6775 1675);
DISPLAY 0.680851 (-6775 1675);
DISPLAY INVISIBLE (-6775 1675);
FORCEPROP 2 LASTPIN (-6875 1600) $PN 1
J 0
(-6865 1610);
DISPLAY 0.808511 (-6865 1610);
FORCEPROP 2 LASTPIN (-7025 1600) $PN 2
J 2
(-7035 1610);
DISPLAY 0.808511 (-7035 1610);
FORCEPROP 2 LAST VALUE DIFF BUS_0.22UF
J 2
(-7100 1600);
DISPLAY 0.553191 (-7100 1600);
FORCEPROP 1 LAST CDS_LMAN_SYM_OUTLINE -25,50,25,-50
J 2
(-6950 1600);
DISPLAY 0.468085 (-6950 1600);
PAINT GREEN (-6950 1600);
DISPLAY INVISIBLE (-6950 1600);
FORCEPROP 2 LAST CDS_LIB pure_quanta
J 2
(-6950 1600);
DISPLAY INVISIBLE (-6950 1600);
FORCEPROP 1 LAST PIN_NAMES_ROTATE TRUE
J 2
(-6950 1600);
DISPLAY 0.489362 (-6950 1600);
PAINT GREEN (-6950 1600);
DISPLAY INVISIBLE (-6950 1600);
FORCEPROP 2 LAST VOLTAGE 6.3V
J 2
(-7300 1650);
DISPLAY 0.553191 (-7300 1650);
DISPLAY INVISIBLE (-7300 1650);
FORCEPROP 1 LAST MATERIAL X6S
J 2
(-6941 1679);
DISPLAY 0.574468 (-6941 1679);
PAINT GREEN (-6941 1679);
DISPLAY INVISIBLE (-6941 1679);
FORCEPROP 2 LAST PACK_TYPE C0201
J 2
(-7125 1650);
DISPLAY 0.553191 (-7125 1650);
DISPLAY INVISIBLE (-7125 1650);
FORCEPROP 2 LAST TOLERANCE 20%
J 2
(-7025 1650);
DISPLAY 0.553191 (-7025 1650);
DISPLAY INVISIBLE (-7025 1650);
FORCEPROP 1 LAST PATH I97
J 2
(-6950 1600);
DISPLAY 0.723404 (-6950 1600);
DISPLAY INVISIBLE (-6950 1600);
FORCEPROP 1 LAST PART_NUMBER SP_CH4221MEE01
J 2
(-7066 1688);
DISPLAY 0.574468 (-7066 1688);
PAINT GREEN (-7066 1688);
DISPLAY INVISIBLE (-7066 1688);
FORCEPROP 1 LAST LOCATION C6650
J 0
(-6700 1675);
DISPLAY 1.021277 (-6700 1675);
DISPLAY INVISIBLE (-6700 1675);
FORCEADD TAP..1
R 2
(-7925 1800);
FORCEPROP 3 LASTPIN (-7875 1800) SIG_NAME P5E_CPU1_P0_TX_BUF_DN<9>
J 0
(-7865 1810);
DISPLAY 0.659574 (-7865 1810);
PAINT MONO (-7865 1810);
DISPLAY INVISIBLE (-7865 1810);
FORCEPROP 1 LASTPIN (-7875 1800) BN 9
J 2
(-7863 1808);
DISPLAY 0.680851 (-7863 1808);
PAINT GREEN (-7863 1808);
FORCEPROP 2 LAST CDS_LIB standard
J 0
(-7925 1800);
DISPLAY INVISIBLE (-7925 1800);
FORCEPROP 1 LAST BODY_TYPE PLUMBING
J 2
(-7925 1850);
DISPLAY 0.872340 (-7925 1850);
PAINT GREEN (-7925 1850);
DISPLAY INVISIBLE (-7925 1850);
FORCEPROP 1 LAST HDL_TAP TRUE
J 2
(-8250 1675);
DISPLAY 0.872340 (-8250 1675);
DISPLAY INVISIBLE (-8250 1675);
FORCEPROP 1 LAST PATH I98
J 2
(-7923 1800);
DISPLAY 0.872340 (-7923 1800);
PAINT GREEN (-7923 1800);
DISPLAY INVISIBLE (-7923 1800);
FORCEADD TAP..1
R 2
(-7925 2000);
FORCEPROP 3 LASTPIN (-7875 2000) SIG_NAME P5E_CPU1_P0_TX_BUF_DN<8>
J 0
(-7865 2010);
DISPLAY 0.659574 (-7865 2010);
PAINT MONO (-7865 2010);
DISPLAY INVISIBLE (-7865 2010);
FORCEPROP 1 LASTPIN (-7875 2000) BN 8
J 2
(-7863 2008);
DISPLAY 0.680851 (-7863 2008);
PAINT GREEN (-7863 2008);
FORCEPROP 2 LAST CDS_LIB standard
J 0
(-7925 2000);
DISPLAY INVISIBLE (-7925 2000);
FORCEPROP 1 LAST BODY_TYPE PLUMBING
J 2
(-7925 2050);
DISPLAY 0.872340 (-7925 2050);
PAINT GREEN (-7925 2050);
DISPLAY INVISIBLE (-7925 2050);
FORCEPROP 1 LAST HDL_TAP TRUE
J 2
(-8250 1875);
DISPLAY 0.872340 (-8250 1875);
DISPLAY INVISIBLE (-8250 1875);
FORCEPROP 1 LAST PATH I99
J 2
(-7923 2000);
DISPLAY 0.872340 (-7923 2000);
PAINT GREEN (-7923 2000);
DISPLAY INVISIBLE (-7923 2000);
FORCEADD QUANTA_TITLE_BLOCK_C..1
(0 0);
FORCEPROP 0 LAST CDS_CON_LAST_MODIFIED Thu Sep 14 16:12:54 2023
J 0
(-1885 15);
DISPLAY INVISIBLE (-1885 15);
FORCEPROP 1 LAST CUSTOM_TXT_CDS <CON_LAST_MODIFIED>
J 0
(-1885 15);
DISPLAY 0.978723 (-1885 15);
FORCEPROP 2 LAST CUSTOM_TXT_CDS <XR_PAGE_TITLE>
J 0
(-7890 5250);
DISPLAY 0.638298 (-7890 5250);
PAINT PINK (-7890 5250);
DISPLAY INVISIBLE (-7890 5250);
FORCEPROP 1 LAST CUSTOM_TXT_CDS <NAME_2>
J 0
(-3175 50);
FORCEPROP 1 LAST CUSTOM_TXT_CDS <NAME_1>
J 0
(-3175 175);
FORCEPROP 1 LAST CUSTOM_TXT_CDS <Q_NUMBER>
J 0
(-1403 103);
DISPLAY 1.212766 (-1403 103);
FORCEPROP 1 LAST CUSTOM_TXT_CDS <Q_PROJ>
J 0
(-2382 102);
DISPLAY 1.212766 (-2382 102);
FORCEPROP 1 LAST CUSTOM_TXT_CDS <Q_REV>
J 0
(-184 103);
DISPLAY 1.212766 (-184 103);
FORCEPROP 1 LAST CUSTOM_TXT_CDS <CON_PAGE_NUM> OF <CON_TOTAL_PAGES>
J 0
(-446 18);
DISPLAY 0.978723 (-446 18);
FORCEPROP 1 LAST Q_TITLE RETIMER_CPU1_P0(4)
J 0
(-9366 26);
DISPLAY 2.446809 (-9366 26);
PAINT GREEN (-9366 26);
FORCEPROP 2 LAST PAGE_BORDER TRUE
J 0
(-7890 5250);
DISPLAY 0.638298 (-7890 5250);
PAINT PINK (-7890 5250);
DISPLAY INVISIBLE (-7890 5250);
FORCEPROP 1 LAST CDS_LMAN_SYM_OUTLINE -9475,6775,100,-125
J 0
(0 0);
DISPLAY 0.468085 (0 0);
PAINT GREEN (0 0);
DISPLAY INVISIBLE (0 0);
FORCEPROP 2 LAST CDS_LIB pure_quanta
J 0
(0 0);
DISPLAY INVISIBLE (0 0);
FORCEPROP 2 LAST CDS_XR_PAGE_TITLE CR-320 : @T6G_MB_LIB.T6G(SCH_1):PAGE320
J 0
(-7890 5250);
DISPLAY 0.638298 (-7890 5250);
PAINT PINK (-7890 5250);
DISPLAY INVISIBLE (-7890 5250);
FORCEPROP 1 LAST Q_DEPT BU9
J 1
(-3763 49);
DISPLAY 1.957447 (-3763 49);
PAINT GREEN (-3763 49);
DISPLAY INVISIBLE (-3763 49);
FORCEPROP 1 LAST COMMENT_BODY TRUE
J 0
(12 -13);
DISPLAY 0.978723 (12 -13);
PAINT GREEN (12 -13);
DISPLAY INVISIBLE (12 -13);
WIRE 17 -1 (-3375 1800)(-3375 2000);
WIRE 17 -1 (-3375 1600)(-3375 1800);
WIRE 17 -1 (-4225 2000)(-3375 2000);
FORCEPROP 2 LAST SIG_NAME P5E_CPU1_P0_TX_BUF_DN<7:0>
J 0
(-4210 2010);
DISPLAY 0.680851 (-4210 2010);
PAINT WHITE (-4210 2010);
WIRE 17 -1 (-1550 1200)(-1550 1400);
WIRE 17 -1 (-1550 1200)(-1550 1000);
WIRE 17 -1 (-1550 1600)(-1550 1400);
WIRE 17 -1 (-1550 1800)(-1550 1600);
WIRE 17 -1 (-1550 1000)(-1550 800);
WIRE 17 -1 (-1550 800)(-1550 600);
WIRE 17 -1 (-1550 2000)(-1550 1800);
FORCEPROP 2 LAST SIG_NAME P5E_CPU1_P0_TX_BUF_C_DN<7:0>
J 0
(-1560 2010);
DISPLAY 0.680851 (-1560 2010);
PAINT WHITE (-1560 2010);
WIRE 17 -1 (-3375 600)(-3375 800);
WIRE 17 -1 (-3375 800)(-3375 1000);
WIRE 17 -1 (-3375 1000)(-3375 1200);
WIRE 17 -1 (-3375 1200)(-3375 1400);
WIRE 17 -1 (-3375 1400)(-3375 1600);
WIRE 17 -1 (-3125 850)(-3125 650);
WIRE 17 -1 (-3125 1050)(-3125 850);
WIRE 17 -1 (-3125 1250)(-3125 1050);
WIRE 17 -1 (-3125 1250)(-3125 1450);
WIRE 17 -1 (-3125 1650)(-3125 1450);
WIRE 17 -1 (-3125 1850)(-3125 1650);
WIRE 17 -1 (-3125 2050)(-3125 1850);
WIRE 17 -1 (-4225 2050)(-3125 2050);
FORCEPROP 2 LAST SIG_NAME P5E_CPU1_P0_TX_BUF_DP<7:0>
J 0
(-4210 2060);
DISPLAY 0.680851 (-4210 2060);
PAINT WHITE (-4210 2060);
WIRE 17 -1 (-1750 850)(-1750 650);
WIRE 17 -1 (-1750 1050)(-1750 850);
WIRE 17 -1 (-1750 1250)(-1750 1050);
WIRE 17 -1 (-1750 1250)(-1750 1450);
WIRE 17 -1 (-1750 1650)(-1750 1450);
WIRE 17 -1 (-1750 1850)(-1750 1650);
WIRE 17 -1 (-1750 2050)(-1750 1850);
WIRE 17 -1 (-1750 2050)(-650 2050);
FORCEPROP 2 LAST SIG_NAME P5E_CPU1_P0_TX_BUF_C_DP<7:0>
J 0
(-1560 2060);
DISPLAY 0.680851 (-1560 2060);
PAINT WHITE (-1560 2060);
WIRE 17 -1 (-7975 625)(-7975 825);
WIRE 17 -1 (-7975 825)(-7975 1025);
WIRE 17 -1 (-7975 1025)(-7975 1225);
WIRE 17 -1 (-7975 1225)(-7975 1425);
WIRE 17 -1 (-7975 1425)(-7975 1625);
WIRE 17 -1 (-7975 1625)(-7975 1825);
WIRE 17 -1 (-7975 1825)(-7975 2025);
WIRE 17 -1 (-8825 2025)(-7975 2025);
FORCEPROP 2 LAST SIG_NAME P5E_CPU1_P0_TX_BUF_DN<15:8>
J 0
(-8810 2035);
DISPLAY 0.680851 (-8810 2035);
PAINT WHITE (-8810 2035);
WIRE 17 -1 (-7725 875)(-7725 675);
WIRE 17 -1 (-7725 1075)(-7725 875);
WIRE 17 -1 (-7725 1275)(-7725 1075);
WIRE 17 -1 (-7725 1275)(-7725 1475);
WIRE 17 -1 (-7725 1675)(-7725 1475);
WIRE 17 -1 (-7725 1875)(-7725 1675);
WIRE 17 -1 (-7725 2075)(-7725 1875);
WIRE 17 -1 (-8825 2075)(-7725 2075);
FORCEPROP 2 LAST SIG_NAME P5E_CPU1_P0_TX_BUF_DP<15:8>
J 0
(-8810 2085);
DISPLAY 0.680851 (-8810 2085);
PAINT WHITE (-8810 2085);
WIRE 17 -1 (-6150 825)(-6150 625);
WIRE 17 -1 (-6150 1025)(-6150 825);
WIRE 17 -1 (-6150 1225)(-6150 1025);
WIRE 17 -1 (-6150 1225)(-6150 1425);
WIRE 17 -1 (-6150 1625)(-6150 1425);
WIRE 17 -1 (-6150 1825)(-6150 1625);
WIRE 17 -1 (-6150 2025)(-6150 1825);
FORCEPROP 2 LAST SIG_NAME P5E_CPU1_P0_TX_BUF_C_DN<15:8>
J 0
(-6160 2035);
DISPLAY 0.680851 (-6160 2035);
PAINT WHITE (-6160 2035);
WIRE 17 -1 (-6350 875)(-6350 675);
WIRE 17 -1 (-6350 1075)(-6350 875);
WIRE 17 -1 (-6350 1275)(-6350 1075);
WIRE 17 -1 (-6350 1275)(-6350 1475);
WIRE 17 -1 (-6350 1675)(-6350 1475);
WIRE 17 -1 (-6350 1875)(-6350 1675);
WIRE 17 -1 (-6350 2075)(-6350 1875);
WIRE 17 -1 (-6350 2075)(-5250 2075);
FORCEPROP 2 LAST SIG_NAME P5E_CPU1_P0_TX_BUF_C_DP<15:8>
J 0
(-6160 2085);
DISPLAY 0.680851 (-6160 2085);
PAINT WHITE (-6160 2085);
WIRE 17 -1 (-6725 5650)(-5850 5650);
FORCEPROP 2 LAST SIG_NAME P5E_CPU1_P0_TX_BUF_DN<15:8>
J 0
(-6735 5660);
DISPLAY 0.680851 (-6735 5660);
PAINT WHITE (-6735 5660);
WIRE 17 -1 (-6925 5750)(-6925 5400);
WIRE 17 -1 (-6925 5750)(-5825 5750);
FORCEPROP 2 LAST SIG_NAME P5E_CPU1_P0_TX_BUF_DP<15:8>
J 0
(-6735 5760);
DISPLAY 0.680851 (-6735 5760);
PAINT WHITE (-6735 5760);
WIRE 17 -1 (-6725 5650)(-6725 5300);
WIRE 17 -1 (-6925 4000)(-6925 3650);
WIRE 17 -1 (-6925 4350)(-6925 4000);
WIRE 17 -1 (-6925 3650)(-6925 3300);
WIRE 17 -1 (-6925 4350)(-6925 4700);
WIRE 17 -1 (-6925 5050)(-6925 4700);
WIRE 17 -1 (-6925 5400)(-6925 5050);
WIRE 17 -1 (-6725 3900)(-6725 3550);
WIRE 17 -1 (-6725 4250)(-6725 3900);
WIRE 17 -1 (-6725 3550)(-6725 3200);
WIRE 17 -1 (-6725 4250)(-6725 4600);
WIRE 17 -1 (-6725 4950)(-6725 4600);
WIRE 17 -1 (-6725 5300)(-6725 4950);
WIRE 17 -1 (-1750 5725)(-650 5725);
FORCEPROP 2 LAST SIG_NAME P5E_CPU1_P0_TX_BUF_DP<7:0>
J 0
(-1560 5735);
DISPLAY 0.680851 (-1560 5735);
PAINT WHITE (-1560 5735);
WIRE 17 -1 (-1550 5625)(-675 5625);
FORCEPROP 2 LAST SIG_NAME P5E_CPU1_P0_TX_BUF_DN<7:0>
J 0
(-1560 5635);
DISPLAY 0.680851 (-1560 5635);
PAINT WHITE (-1560 5635);
WIRE 17 -1 (-1550 5625)(-1550 5275);
WIRE 17 -1 (-1750 5375)(-1750 5025);
WIRE 17 -1 (-1750 5725)(-1750 5375);
WIRE 17 -1 (-1750 5025)(-1750 4675);
WIRE 17 -1 (-1750 4325)(-1750 4675);
WIRE 17 -1 (-1750 4325)(-1750 3975);
WIRE 17 -1 (-1750 3975)(-1750 3625);
WIRE 17 -1 (-1750 3625)(-1750 3275);
WIRE 17 -1 (-1550 4225)(-1550 4575);
WIRE 17 -1 (-1550 4225)(-1550 3875);
WIRE 17 -1 (-1550 4925)(-1550 4575);
WIRE 17 -1 (-1550 5275)(-1550 4925);
WIRE 17 -1 (-1550 3875)(-1550 3525);
WIRE 17 -1 (-1550 3525)(-1550 3175);
WIRE 17 -1 (-1550 2000)(-650 2000);
WIRE 17 -1 (-6150 2025)(-5250 2025);
WIRE 16 -1 (-7250 4925)(-6825 4925);
WIRE 16 -1 (-7250 4575)(-6825 4575);
WIRE 16 -1 (-2075 3150)(-1650 3150);
WIRE 16 -1 (-2075 3600)(-1850 3600);
WIRE 16 -1 (-2075 3950)(-1850 3950);
WIRE 16 -1 (-2075 3850)(-1650 3850);
WIRE 16 -1 (-2075 4650)(-1850 4650);
WIRE 16 -1 (-2075 4550)(-1650 4550);
WIRE 16 -1 (-2075 4900)(-1650 4900);
WIRE 16 -1 (-7250 4325)(-7025 4325);
WIRE 16 -1 (-7250 4675)(-7025 4675);
WIRE 16 -1 (-7250 3975)(-7025 3975);
WIRE 16 -1 (-7250 5025)(-7025 5025);
WIRE 16 -1 (-7250 3875)(-6825 3875);
WIRE 16 -1 (-2075 5350)(-1850 5350);
WIRE 16 -1 (-7250 4225)(-6825 4225);
WIRE 16 -1 (-7250 3275)(-7025 3275);
WIRE 16 -1 (-7250 3175)(-6825 3175);
WIRE 16 -1 (-2075 3250)(-1850 3250);
WIRE 16 -1 (-2075 3500)(-1650 3500);
WIRE 16 -1 (-2075 4200)(-1650 4200);
WIRE 16 -1 (-2075 4300)(-1850 4300);
WIRE 16 -1 (-2075 5000)(-1850 5000);
WIRE 16 -1 (-2075 5250)(-1650 5250);
WIRE 16 -1 (-2075 5600)(-1650 5600);
WIRE 16 -1 (-2075 5700)(-1850 5700);
WIRE 16 -1 (-7250 3525)(-6825 3525);
WIRE 16 -1 (-7250 3625)(-7025 3625);
WIRE 16 -1 (-7250 5725)(-7025 5725);
WIRE 16 -1 (-7250 5275)(-6825 5275);
WIRE 16 -1 (-7250 5375)(-7025 5375);
WIRE 16 -1 (-7250 5625)(-6825 5625);
WIRE 16 -1 (-6875 1250)(-6450 1250);
WIRE 16 -1 (-6875 2050)(-6450 2050);
WIRE 16 -1 (-7025 2050)(-7625 2050);
WIRE 16 -1 (-6875 2000)(-6250 2000);
WIRE 16 -1 (-6875 1800)(-6250 1800);
WIRE 16 -1 (-6875 1850)(-6450 1850);
WIRE 16 -1 (-6875 1600)(-6250 1600);
WIRE 16 -1 (-6875 1650)(-6450 1650);
WIRE 16 -1 (-6875 1450)(-6450 1450);
WIRE 16 -1 (-6875 1400)(-6250 1400);
WIRE 16 -1 (-6875 1200)(-6250 1200);
WIRE 16 -1 (-7025 1850)(-7625 1850);
WIRE 16 -1 (-7025 1650)(-7625 1650);
WIRE 16 -1 (-7025 1450)(-7625 1450);
WIRE 16 -1 (-7025 1250)(-7625 1250);
WIRE 16 -1 (-6875 1050)(-6450 1050);
WIRE 16 -1 (-7025 1050)(-7625 1050);
WIRE 16 -1 (-6875 1000)(-6250 1000);
WIRE 16 -1 (-6875 850)(-6450 850);
WIRE 16 -1 (-6875 800)(-6250 800);
WIRE 16 -1 (-6875 650)(-6450 650);
WIRE 16 -1 (-6875 600)(-6250 600);
WIRE 16 -1 (-7025 850)(-7625 850);
WIRE 16 -1 (-7025 650)(-7625 650);
WIRE 16 -1 (-7025 2000)(-7875 2000);
WIRE 16 -1 (-7025 1800)(-7875 1800);
WIRE 16 -1 (-7025 1600)(-7875 1600);
WIRE 16 -1 (-7025 1400)(-7875 1400);
WIRE 16 -1 (-7025 1200)(-7875 1200);
WIRE 16 -1 (-7025 1000)(-7875 1000);
WIRE 16 -1 (-7025 800)(-7875 800);
WIRE 16 -1 (-7025 600)(-7875 600);
WIRE 16 -1 (-2275 1225)(-1850 1225);
WIRE 16 -1 (-2275 2025)(-1850 2025);
WIRE 16 -1 (-2275 1975)(-1650 1975);
WIRE 16 -1 (-2275 1825)(-1850 1825);
WIRE 16 -1 (-2275 1775)(-1650 1775);
WIRE 16 -1 (-2275 1625)(-1850 1625);
WIRE 16 -1 (-2275 1575)(-1650 1575);
WIRE 16 -1 (-2275 1425)(-1850 1425);
WIRE 16 -1 (-2425 2025)(-3025 2025);
WIRE 16 -1 (-2425 1825)(-3025 1825);
WIRE 16 -1 (-2425 1625)(-3025 1625);
WIRE 16 -1 (-2425 1425)(-3025 1425);
WIRE 16 -1 (-2425 1225)(-3025 1225);
WIRE 16 -1 (-2425 1975)(-3275 1975);
WIRE 16 -1 (-2425 1575)(-3275 1575);
WIRE 16 -1 (-2425 1375)(-3275 1375);
WIRE 16 -1 (-2275 1025)(-1850 1025);
WIRE 16 -1 (-2275 975)(-1650 975);
WIRE 16 -1 (-2275 775)(-1650 775);
WIRE 16 -1 (-2275 825)(-1850 825);
WIRE 16 -1 (-2275 575)(-1650 575);
WIRE 16 -1 (-2275 625)(-1850 625);
WIRE 16 -1 (-2425 1025)(-3025 1025);
WIRE 16 -1 (-2425 825)(-3025 825);
WIRE 16 -1 (-2425 625)(-3025 625);
WIRE 16 -1 (-2425 1175)(-3275 1175);
WIRE 16 -1 (-2425 975)(-3275 975);
WIRE 16 -1 (-2425 775)(-3275 775);
WIRE 16 -1 (-2425 575)(-3275 575);
WIRE 16 -1 (-2275 1175)(-1650 1175);
WIRE 16 -1 (-2275 1375)(-1650 1375);
WIRE 16 -1 (-2425 1775)(-3275 1775);
FORCENOTE
RETIMER TO EXAMAX
(-8600 2825) 0;
DISPLAY LEFT (-8600 2825);
DISPLAY 3.148936 (-8600 2825);
FORCENOTE
P5E_CPU1_P0_TX_BUF_DP/DN<0-15> LANE REVERSAL
(-9200 6400) 0;
DISPLAY LEFT (-9200 6400);
DISPLAY 2.000000 (-9200 6400);
FORCENOTE
RETIMER TO EXAMAX
(-3600 2800) 0;
DISPLAY LEFT (-3600 2800);
DISPLAY 3.148936 (-3600 2800);
QUIT
